FILE_TYPE = MACRO_DRAWING;
SET COLOR_WIRE YELLOW;
SET COLOR_PROP MONO;
SET COLOR_DOT WHITE;
SET COLOR_ARC YELLOW;
SET COLOR_BODY GREEN;
SET COLOR_NOTE MONO;
SET PROP_DISPLAY VALUE;
SET PAGE_NUMBER P229;
FORCEADD PVTT_GHJ..1
(3475 3650);
FORCEPROP 3 LASTPIN (3475 3600) SIG_NAME PVTT_GHJ\g
J 0
(3485 3610);
DISPLAY 0.659574 (3485 3610);
PAINT MONO (3485 3610);
DISPLAY INVISIBLE (3485 3610);
FORCEPROP 1 LAST VOLTAGE 0.6V
J 0
(3430 3607);
DISPLAY 0.340426 (3430 3607);
PAINT SKYBLUE (3430 3607);
DISPLAY INVISIBLE (3430 3607);
FORCEPROP 2 LAST BOM_COST MEM_VRD_PVDDQ_GHJ
J 0
(3550 3750);
PAINT MONO (3550 3750);
DISPLAY INVISIBLE (3550 3750);
FORCEPROP 2 LAST CDS_LIB mstr_symbols
J 0
(3475 3650);
PAINT ORANGE (3475 3650);
DISPLAY INVISIBLE (3475 3650);
FORCEPROP 1 LAST BODY_TYPE PLUMBING
J 0
(3430 3607);
DISPLAY 0.340426 (3430 3607);
PAINT GREEN (3430 3607);
DISPLAY INVISIBLE (3430 3607);
FORCEPROP 1 LAST PATH I10
J 0
(3525 3675);
DISPLAY 0.872340 (3525 3675);
PAINT AQUA (3525 3675);
DISPLAY INVISIBLE (3525 3675);
FORCEPROP 1 LAST HDL_POWER PVTT_GHJ
J 1
(3475 3700);
DISPLAY 0.872340 (3475 3700);
PAINT GREEN (3475 3700);
DISPLAY INVISIBLE (3475 3700);
FORCEPROP 2 LAST ROOM VTT_GHJ_VR
J 0
(3725 3750);
PAINT ORANGE (3725 3750);
DISPLAY INVISIBLE (3725 3750);
FORCEADD RES..2
(3450 2025);
FORCEPROP 1 LASTPIN (3450 1925) $PN 2
J 0
(3455 1935);
DISPLAY 0.617021 (3455 1935);
PAINT WHITE (3455 1935);
FORCEPROP 1 LAST PART_NUMBER G21796-016
J 0
(3490 1900);
DISPLAY 0.617021 (3490 1900);
PAINT BLUE (3490 1900);
FORCEPROP 1 LAST MATERIAL CHIP
J 0
(3490 1950);
DISPLAY 0.617021 (3490 1950);
PAINT SKYBLUE (3490 1950);
FORCEPROP 1 LAST WATTAGE 1/16W
J 0
(3490 2000);
DISPLAY 0.617021 (3490 2000);
PAINT SKYBLUE (3490 2000);
FORCEPROP 1 LAST PACK_TYPE 0402
J 0
(3640 2000);
DISPLAY 0.617021 (3640 2000);
PAINT SKYBLUE (3640 2000);
FORCEPROP 1 LASTPIN (3450 2125) $PN 1
J 0
(3455 2087);
DISPLAY 0.617021 (3455 2087);
PAINT WHITE (3455 2087);
FORCEPROP 1 LAST TOLERANCE 1%
J 0
(3495 2050);
DISPLAY 0.617021 (3495 2050);
PAINT SKYBLUE (3495 2050);
FORCEPROP 1 LAST LOCATION R4G17
J 0
(3495 2150);
DISPLAY 0.617021 (3495 2150);
PAINT AQUA (3495 2150);
FORCEPROP 1 LAST VALUE 10.0K
J 0
(3495 2100);
DISPLAY 0.617021 (3495 2100);
PAINT SKYBLUE (3495 2100);
FORCEPROP 2 LAST CDS_LIB mstr_discrete
J 0
(3450 2025);
PAINT ORANGE (3450 2025);
DISPLAY INVISIBLE (3450 2025);
FORCEPROP 2 LAST ROOM VTT_GHJ_PWR_VR
J 0
(3500 2200);
DISPLAY 1.021277 (3500 2200);
PAINT ORANGE (3500 2200);
DISPLAY INVISIBLE (3500 2200);
FORCEPROP 2 LAST BOM_COST MEM_VRD_VTT_GHJ
J 0
(3500 2250);
DISPLAY 1.021277 (3500 2250);
PAINT ORANGE (3500 2250);
DISPLAY INVISIBLE (3500 2250);
FORCEPROP 2 LAST SEC_TYPE 0402
J 0
(3500 2246);
DISPLAY 1.021277 (3500 2246);
PAINT ORANGE (3500 2246);
DISPLAY INVISIBLE (3500 2246);
FORCEPROP 2 LAST SEC 1
J 0
(3500 2246);
DISPLAY 0.680851 (3500 2246);
PAINT MONO (3500 2246);
DISPLAY INVISIBLE (3500 2246);
FORCEPROP 1 LAST PATH I14
J 0
(3500 2200);
DISPLAY 0.978723 (3500 2200);
PAINT WHITE (3500 2200);
DISPLAY INVISIBLE (3500 2200);
FORCEPROP 2 LAST CDS_LOCATION R4G17
J 0
(3495 2150);
DISPLAY 0.617021 (3495 2150);
PAINT AQUA (3495 2150);
DISPLAY INVISIBLE (3495 2150);
FORCEADD CAP..1
R 2
(3825 1625);
FORCEPROP 1 LAST PART_NUMBER A36096-046
J 2
(3775 1475);
DISPLAY 0.617021 (3775 1475);
PAINT BLUE (3775 1475);
FORCEPROP 1 LAST PACK_TYPE 0402LF
J 2
(3775 1425);
DISPLAY 0.617021 (3775 1425);
PAINT SKYBLUE (3775 1425);
FORCEPROP 1 LASTPIN (3825 1525) $PN 2
J 2
(3815 1505);
DISPLAY 0.617021 (3815 1505);
PAINT WHITE (3815 1505);
FORCEPROP 1 LAST MATERIAL X7R
J 2
(3775 1525);
DISPLAY 0.617021 (3775 1525);
PAINT SKYBLUE (3775 1525);
FORCEPROP 1 LASTPIN (3825 1725) $PN 1
J 2
(3815 1705);
DISPLAY 0.617021 (3815 1705);
PAINT WHITE (3815 1705);
FORCEPROP 1 LAST VOLTAGE 50V
J 2
(3775 1625);
DISPLAY 0.617021 (3775 1625);
PAINT SKYBLUE (3775 1625);
FORCEPROP 1 LAST TOLERANCE 10%
J 2
(3775 1575);
DISPLAY 0.617021 (3775 1575);
PAINT SKYBLUE (3775 1575);
FORCEPROP 1 LAST VALUE 1000PF
J 2
(3775 1675);
DISPLAY 0.617021 (3775 1675);
PAINT SKYBLUE (3775 1675);
FORCEPROP 1 LAST LOCATION C4G13
J 2
(3775 1725);
DISPLAY 0.617021 (3775 1725);
PAINT AQUA (3775 1725);
FORCEPROP 2 LAST CDS_LOCATION C4G13
J 2
(3775 1725);
DISPLAY 0.617021 (3775 1725);
PAINT AQUA (3775 1725);
DISPLAY INVISIBLE (3775 1725);
FORCEPROP 2 LAST CDS_LIB mstr_discrete
J 2
(3825 1625);
DISPLAY 0.744681 (3825 1625);
PAINT MONO (3825 1625);
DISPLAY INVISIBLE (3825 1625);
FORCEPROP 2 LAST ROOM VTT_GHJ_PWR_VR
J 2
(3775 1775);
DISPLAY 1.021277 (3775 1775);
PAINT ORANGE (3775 1775);
DISPLAY INVISIBLE (3775 1775);
FORCEPROP 1 LAST PATH I15
J 2
(3775 1775);
DISPLAY 0.978723 (3775 1775);
PAINT WHITE (3775 1775);
DISPLAY INVISIBLE (3775 1775);
FORCEPROP 2 LAST SEC 1
J 2
(3775 1825);
DISPLAY 0.680851 (3775 1825);
PAINT MONO (3775 1825);
DISPLAY INVISIBLE (3775 1825);
FORCEPROP 2 LAST BOM_COST MEM_VRD_VTT_GHJ
J 2
(3775 1825);
DISPLAY 1.021277 (3775 1825);
PAINT ORANGE (3775 1825);
DISPLAY INVISIBLE (3775 1825);
FORCEPROP 2 LAST SEC_TYPE 0402LF
J 2
(3775 1825);
DISPLAY 1.021277 (3775 1825);
PAINT ORANGE (3775 1825);
DISPLAY INVISIBLE (3775 1825);
FORCEADD GND..1
(3825 1400);
FORCEPROP 3 LASTPIN (3825 1450) SIG_NAME GND\g
J 0
(3835 1460);
DISPLAY 0.659574 (3835 1460);
PAINT MONO (3835 1460);
DISPLAY INVISIBLE (3835 1460);
FORCEPROP 1 LAST VOLTAGE 0.0V
J 0
(3780 1357);
DISPLAY 0.340426 (3780 1357);
PAINT SKYBLUE (3780 1357);
DISPLAY INVISIBLE (3780 1357);
FORCEPROP 2 LAST CDS_LIB mstr_symbols
J 0
(3825 1400);
DISPLAY 0.744681 (3825 1400);
PAINT MONO (3825 1400);
DISPLAY INVISIBLE (3825 1400);
FORCEPROP 1 LAST BODY_TYPE PLUMBING
J 0
(3780 1357);
DISPLAY 0.340426 (3780 1357);
PAINT GREEN (3780 1357);
DISPLAY INVISIBLE (3780 1357);
FORCEPROP 1 LAST SIZE 1B
J 0
(3900 1350);
DISPLAY 0.893617 (3900 1350);
PAINT GREEN (3900 1350);
DISPLAY INVISIBLE (3900 1350);
FORCEPROP 1 LAST PATH I16
J 0
(3900 1400);
DISPLAY 0.872340 (3900 1400);
PAINT AQUA (3900 1400);
DISPLAY INVISIBLE (3900 1400);
FORCEPROP 1 LAST HDL_POWER GND
J 0
(3825 1550);
DISPLAY 0.893617 (3825 1550);
PAINT GREEN (3825 1550);
DISPLAY INVISIBLE (3825 1550);
FORCEADD CAP..1
(3925 1075);
FORCEPROP 1 LAST MATERIAL X6S
J 0
(3975 975);
DISPLAY 0.617021 (3975 975);
PAINT SKYBLUE (3975 975);
FORCEPROP 1 LASTPIN (3925 975) $PN 2
J 0
(3935 955);
DISPLAY 0.617021 (3935 955);
PAINT WHITE (3935 955);
FORCEPROP 1 LAST PART_NUMBER C95333-002
R 1
J 0
(3875 925);
DISPLAY 0.617021 (3875 925);
PAINT BLUE (3875 925);
FORCEPROP 1 LASTPIN (3925 1175) $PN 1
J 0
(3935 1155);
DISPLAY 0.617021 (3935 1155);
PAINT WHITE (3935 1155);
FORCEPROP 1 LAST VOLTAGE 4V
J 0
(3975 1075);
DISPLAY 0.617021 (3975 1075);
PAINT SKYBLUE (3975 1075);
FORCEPROP 1 LAST VALUE 22UF
J 0
(3975 1125);
DISPLAY 0.617021 (3975 1125);
PAINT SKYBLUE (3975 1125);
FORCEPROP 1 LAST TOLERANCE 20%
J 0
(3975 1025);
DISPLAY 0.617021 (3975 1025);
PAINT SKYBLUE (3975 1025);
FORCEPROP 1 LAST LOCATION C4G20
J 0
(3975 1175);
DISPLAY 0.617021 (3975 1175);
PAINT AQUA (3975 1175);
FORCEPROP 1 LAST PACK_TYPE 0805LF
J 0
(3975 925);
DISPLAY 0.617021 (3975 925);
PAINT SKYBLUE (3975 925);
FORCEPROP 1 LAST PATH I17
J 0
(3975 1225);
DISPLAY 0.978723 (3975 1225);
PAINT WHITE (3975 1225);
DISPLAY INVISIBLE (3975 1225);
FORCEPROP 2 LAST CDS_LOCATION C4G20
J 0
(3975 1175);
DISPLAY 0.617021 (3975 1175);
PAINT AQUA (3975 1175);
DISPLAY INVISIBLE (3975 1175);
FORCEPROP 2 LAST CDS_LIB mstr_discrete
J 0
(3925 1075);
PAINT ORANGE (3925 1075);
DISPLAY INVISIBLE (3925 1075);
FORCEPROP 2 LAST ROOM VTT_GHJ_PWR_VR
J 0
(3995 1230);
DISPLAY 1.021277 (3995 1230);
PAINT ORANGE (3995 1230);
DISPLAY INVISIBLE (3995 1230);
FORCEPROP 2 LAST BOM_COST MEM_VRD_VTT_GHJ
J 0
(3995 1280);
DISPLAY 1.021277 (3995 1280);
PAINT ORANGE (3995 1280);
DISPLAY INVISIBLE (3995 1280);
FORCEPROP 2 LAST SEC 1
J 0
(3976 1295);
DISPLAY 0.680851 (3976 1295);
PAINT MONO (3976 1295);
DISPLAY INVISIBLE (3976 1295);
FORCEPROP 2 LAST SEC_TYPE 0805LF
J 0
(3976 1295);
DISPLAY 1.021277 (3976 1295);
PAINT ORANGE (3976 1295);
DISPLAY INVISIBLE (3976 1295);
FORCEADD GND..1
(3925 675);
FORCEPROP 3 LASTPIN (3925 725) SIG_NAME GND\g
J 0
(3935 735);
DISPLAY 0.659574 (3935 735);
PAINT MONO (3935 735);
DISPLAY INVISIBLE (3935 735);
FORCEPROP 1 LAST VOLTAGE 0.0V
J 0
(3880 632);
DISPLAY 0.340426 (3880 632);
PAINT SKYBLUE (3880 632);
DISPLAY INVISIBLE (3880 632);
FORCEPROP 1 LAST SIZE 1B
J 0
(4000 625);
DISPLAY 0.893617 (4000 625);
PAINT GREEN (4000 625);
DISPLAY INVISIBLE (4000 625);
FORCEPROP 2 LAST CDS_LIB mstr_symbols
J 0
(3925 675);
PAINT ORANGE (3925 675);
DISPLAY INVISIBLE (3925 675);
FORCEPROP 1 LAST BODY_TYPE PLUMBING
J 0
(3880 632);
DISPLAY 0.340426 (3880 632);
PAINT GREEN (3880 632);
DISPLAY INVISIBLE (3880 632);
FORCEPROP 1 LAST PATH I19
J 0
(4000 675);
DISPLAY 0.872340 (4000 675);
PAINT AQUA (4000 675);
DISPLAY INVISIBLE (4000 675);
FORCEPROP 1 LAST HDL_POWER GND
J 0
(3925 825);
DISPLAY 0.893617 (3925 825);
PAINT GREEN (3925 825);
DISPLAY INVISIBLE (3925 825);
FORCEADD OFFPAGE..2
(4950 1825);
FORCEPROP 2 LAST $XR0 230 
J 0
(5139 1825);
DISPLAY 0.638298 (5139 1825);
PAINT MONO (5139 1825);
FORCEPROP 2 LAST $XR1 190 
J 0
(5259 1825);
DISPLAY 0.638298 (5259 1825);
PAINT MONO (5259 1825);
FORCEPROP 1 LAST COMMENT_BODY TRUE
J 0
(4905 1730);
DISPLAY 0.872340 (4905 1730);
PAINT GREEN (4905 1730);
DISPLAY INVISIBLE (4905 1730);
FORCEPROP 2 LAST CDS_LIB mstr_standard
J 0
(4950 1825);
DISPLAY 0.744681 (4950 1825);
PAINT MONO (4950 1825);
DISPLAY INVISIBLE (4950 1825);
FORCEPROP 2 LAST PATH I2
J 0
(5161 1872);
DISPLAY 1.021277 (5161 1872);
PAINT ORANGE (5161 1872);
DISPLAY INVISIBLE (5161 1872);
FORCEPROP 1 LAST OFFPAGE TRUE
J 0
(5275 1700);
DISPLAY 0.872340 (5275 1700);
PAINT GREEN (5275 1700);
DISPLAY INVISIBLE (5275 1700);
FORCEADD CAP..1
(2275 850);
FORCEPROP 1 LASTPIN (2275 750) $PN 2
J 0
(2285 730);
DISPLAY 0.617021 (2285 730);
PAINT WHITE (2285 730);
FORCEPROP 1 LASTPIN (2275 950) $PN 1
J 0
(2285 930);
DISPLAY 0.617021 (2285 930);
PAINT WHITE (2285 930);
FORCEPROP 1 LAST LOCATION C4G21
J 0
(2325 950);
DISPLAY 0.617021 (2325 950);
PAINT AQUA (2325 950);
FORCEPROP 1 LAST VALUE 1.0UF
J 0
(2325 900);
DISPLAY 0.617021 (2325 900);
PAINT SKYBLUE (2325 900);
FORCEPROP 1 LAST TOLERANCE 10%
J 0
(2325 850);
DISPLAY 0.617021 (2325 850);
PAINT SKYBLUE (2325 850);
FORCEPROP 1 LAST PACK_TYPE 0402
J 0
(2325 750);
DISPLAY 0.617021 (2325 750);
PAINT SKYBLUE (2325 750);
FORCEPROP 1 LAST MATERIAL X6S
J 0
(2450 850);
DISPLAY 0.617021 (2450 850);
PAINT SKYBLUE (2450 850);
FORCEPROP 1 LAST PART_NUMBER D97712-011
J 0
(2325 800);
DISPLAY 0.617021 (2325 800);
PAINT BLUE (2325 800);
FORCEPROP 1 LAST VOLTAGE 16V
J 0
(2475 900);
DISPLAY 0.617021 (2475 900);
PAINT SKYBLUE (2475 900);
FORCEPROP 2 LAST CDS_LIB mstr_discrete
J 0
(2275 850);
PAINT ORANGE (2275 850);
DISPLAY INVISIBLE (2275 850);
FORCEPROP 2 LAST CDS_LOCATION C4G21
J 0
(2325 950);
DISPLAY 0.617021 (2325 950);
PAINT AQUA (2325 950);
DISPLAY INVISIBLE (2325 950);
FORCEPROP 1 LAST PATH I21
J 0
(2325 1000);
DISPLAY 0.978723 (2325 1000);
PAINT WHITE (2325 1000);
DISPLAY INVISIBLE (2325 1000);
FORCEPROP 2 LAST ROOM VTT_GHJ_PWR_VR
J 0
(2325 1000);
DISPLAY 1.021277 (2325 1000);
PAINT ORANGE (2325 1000);
DISPLAY INVISIBLE (2325 1000);
FORCEPROP 2 LAST BOM_COST MEM_VRD_VTT_GHJ
J 0
(2325 1050);
DISPLAY 1.021277 (2325 1050);
PAINT ORANGE (2325 1050);
DISPLAY INVISIBLE (2325 1050);
FORCEPROP 2 LAST SEC_TYPE 0402
J 0
(2331 1065);
DISPLAY 1.021277 (2331 1065);
PAINT ORANGE (2331 1065);
DISPLAY INVISIBLE (2331 1065);
FORCEPROP 2 LAST SEC 1
J 0
(2331 1065);
DISPLAY 0.680851 (2331 1065);
PAINT MONO (2331 1065);
DISPLAY INVISIBLE (2331 1065);
FORCEADD GND..1
(2275 600);
FORCEPROP 3 LASTPIN (2275 650) SIG_NAME GND\g
J 0
(2285 660);
DISPLAY 0.659574 (2285 660);
PAINT MONO (2285 660);
DISPLAY INVISIBLE (2285 660);
FORCEPROP 2 LAST CDS_LIB mstr_symbols
J 0
(2275 600);
PAINT ORANGE (2275 600);
DISPLAY INVISIBLE (2275 600);
FORCEPROP 1 LAST VOLTAGE 0.0V
J 0
(2230 557);
DISPLAY 0.340426 (2230 557);
PAINT SKYBLUE (2230 557);
DISPLAY INVISIBLE (2230 557);
FORCEPROP 1 LAST BODY_TYPE PLUMBING
J 0
(2230 557);
DISPLAY 0.340426 (2230 557);
PAINT GREEN (2230 557);
DISPLAY INVISIBLE (2230 557);
FORCEPROP 1 LAST HDL_POWER GND
J 0
(2275 750);
DISPLAY 0.872340 (2275 750);
PAINT GREEN (2275 750);
DISPLAY INVISIBLE (2275 750);
FORCEPROP 1 LAST SIZE 1B
J 0
(2350 550);
DISPLAY 0.872340 (2350 550);
PAINT AQUA (2350 550);
DISPLAY INVISIBLE (2350 550);
FORCEPROP 1 LAST PATH I22
J 0
(2350 600);
DISPLAY 0.872340 (2350 600);
PAINT AQUA (2350 600);
DISPLAY INVISIBLE (2350 600);
FORCEADD GND..1
(1950 600);
FORCEPROP 3 LASTPIN (1950 650) SIG_NAME GND\g
J 0
(1960 660);
DISPLAY 0.659574 (1960 660);
PAINT MONO (1960 660);
DISPLAY INVISIBLE (1960 660);
FORCEPROP 1 LAST VOLTAGE 0.0V
J 0
(1905 557);
DISPLAY 0.340426 (1905 557);
PAINT SKYBLUE (1905 557);
DISPLAY INVISIBLE (1905 557);
FORCEPROP 1 LAST SIZE 1B
J 0
(2025 550);
DISPLAY 0.872340 (2025 550);
PAINT AQUA (2025 550);
DISPLAY INVISIBLE (2025 550);
FORCEPROP 2 LAST CDS_LIB mstr_symbols
J 0
(1950 600);
PAINT ORANGE (1950 600);
DISPLAY INVISIBLE (1950 600);
FORCEPROP 1 LAST BODY_TYPE PLUMBING
J 0
(1905 557);
DISPLAY 0.340426 (1905 557);
PAINT GREEN (1905 557);
DISPLAY INVISIBLE (1905 557);
FORCEPROP 1 LAST PATH I23
J 0
(2025 600);
DISPLAY 0.872340 (2025 600);
PAINT AQUA (2025 600);
DISPLAY INVISIBLE (2025 600);
FORCEPROP 1 LAST HDL_POWER GND
J 0
(1950 750);
DISPLAY 0.872340 (1950 750);
PAINT GREEN (1950 750);
DISPLAY INVISIBLE (1950 750);
FORCEADD MIC5166..1
(1500 1075);
FORCEPROP 2 LASTPIN (1200 975) $PN 6
J 2
(1190 985);
DISPLAY 0.617021 (1190 985);
PAINT ORANGE (1190 985);
FORCEPROP 2 LASTPIN (1200 825) $PN 2
J 2
(1190 835);
DISPLAY 0.617021 (1190 835);
PAINT ORANGE (1190 835);
FORCEPROP 1 LAST PART_NUMBER H55101-001
J 0
(1250 675);
DISPLAY 0.617021 (1250 675);
PAINT BLUE (1250 675);
FORCEPROP 2 LASTPIN (1800 775) $PN 11
J 0
(1810 785);
DISPLAY 0.617021 (1810 785);
PAINT ORANGE (1810 785);
FORCEPROP 2 LASTPIN (1800 925) $PN 8
J 0
(1810 935);
DISPLAY 0.617021 (1810 935);
PAINT ORANGE (1810 935);
FORCEPROP 2 LASTPIN (1800 875) $PN 3
J 0
(1810 885);
DISPLAY 0.617021 (1810 885);
PAINT ORANGE (1810 885);
FORCEPROP 2 LASTPIN (1200 1325) $PN 10
J 2
(1190 1335);
DISPLAY 0.617021 (1190 1335);
PAINT ORANGE (1190 1335);
FORCEPROP 2 LASTPIN (1200 1175) $PN 4
J 2
(1190 1185);
DISPLAY 0.617021 (1190 1185);
PAINT ORANGE (1190 1185);
FORCEPROP 2 LASTPIN (1200 1075) $PN 7
J 2
(1190 1085);
DISPLAY 0.617021 (1190 1085);
PAINT ORANGE (1190 1085);
FORCEPROP 1 LAST LOCATION EU4G2
J 0
(1250 1500);
DISPLAY 0.617021 (1250 1500);
PAINT AQUA (1250 1500);
FORCEPROP 1 LAST MATERIAL IC
J 0
(1250 1450);
DISPLAY 0.617021 (1250 1450);
PAINT SKYBLUE (1250 1450);
FORCEPROP 2 LASTPIN (1800 1325) $PN 9
J 0
(1810 1335);
DISPLAY 0.617021 (1810 1335);
PAINT ORANGE (1810 1335);
FORCEPROP 2 LASTPIN (1800 1225) $PN 1
J 0
(1810 1235);
DISPLAY 0.617021 (1810 1235);
PAINT ORANGE (1810 1235);
FORCEPROP 2 LASTPIN (1800 1025) $PN 5
J 0
(1810 1035);
DISPLAY 0.617021 (1810 1035);
PAINT ORANGE (1810 1035);
FORCEPROP 2 LAST CDS_LOCATION EU4G2
J 0
(1250 1500);
DISPLAY 0.617021 (1250 1500);
PAINT AQUA (1250 1500);
DISPLAY INVISIBLE (1250 1500);
FORCEPROP 1 LAST CDS_LMAN_SYM_OUTLINE -250,350,250,-350
J 0
(1500 1075);
DISPLAY 0.468085 (1500 1075);
PAINT GREEN (1500 1075);
DISPLAY INVISIBLE (1500 1075);
FORCEPROP 2 LAST CDS_LIB mstr_vreg
J 0
(1500 1075);
PAINT ORANGE (1500 1075);
DISPLAY INVISIBLE (1500 1075);
FORCEPROP 2 LAST ROOM VTT_GHJ_PWR_VR
J 0
(1250 1534);
DISPLAY 1.021277 (1250 1534);
PAINT ORANGE (1250 1534);
DISPLAY INVISIBLE (1250 1534);
FORCEPROP 1 LAST PACK_TYPE DFN
J 0
(1250 1550);
PAINT SKYBLUE (1250 1550);
DISPLAY INVISIBLE (1250 1550);
FORCEPROP 2 LAST SEC_TYPE DFN
J 0
(1265 1557);
DISPLAY 1.021277 (1265 1557);
PAINT ORANGE (1265 1557);
DISPLAY INVISIBLE (1265 1557);
FORCEPROP 2 LAST BOM_COST MEM_VRD_VTT_GHJ
J 0
(1250 1582);
DISPLAY 1.021277 (1250 1582);
PAINT ORANGE (1250 1582);
DISPLAY INVISIBLE (1250 1582);
FORCEPROP 2 LAST SEC 1
J 0
(1265 1557);
DISPLAY 0.680851 (1265 1557);
PAINT MONO (1265 1557);
DISPLAY INVISIBLE (1265 1557);
FORCEPROP 1 LAST PATH I24
J 0
(1700 1450);
PAINT GREEN (1700 1450);
DISPLAY INVISIBLE (1700 1450);
FORCEADD CAP..1
(425 2375);
FORCEPROP 1 LASTPIN (425 2275) $PN 2
J 0
(435 2255);
DISPLAY 0.617021 (435 2255);
PAINT WHITE (435 2255);
FORCEPROP 1 LASTPIN (425 2475) $PN 1
J 0
(435 2455);
DISPLAY 0.617021 (435 2455);
PAINT WHITE (435 2455);
FORCEPROP 1 LAST LOCATION C6U14
J 0
(475 2475);
DISPLAY 0.617021 (475 2475);
PAINT AQUA (475 2475);
FORCEPROP 1 LAST PART_NUMBER E15431-001
J 0
(475 2225);
DISPLAY 0.617021 (475 2225);
PAINT BLUE (475 2225);
FORCEPROP 1 LAST VALUE 10UF
J 0
(475 2425);
DISPLAY 0.617021 (475 2425);
PAINT SKYBLUE (475 2425);
FORCEPROP 1 LAST TOLERANCE 20%
J 0
(475 2325);
DISPLAY 0.617021 (475 2325);
PAINT SKYBLUE (475 2325);
FORCEPROP 1 LAST PACK_TYPE 0603LF
J 0
(475 2175);
DISPLAY 0.617021 (475 2175);
PAINT SKYBLUE (475 2175);
FORCEPROP 1 LAST VOLTAGE 4V
J 0
(475 2375);
DISPLAY 0.617021 (475 2375);
PAINT SKYBLUE (475 2375);
FORCEPROP 1 LAST MATERIAL X6S
J 0
(475 2275);
DISPLAY 0.617021 (475 2275);
PAINT SKYBLUE (475 2275);
FORCEPROP 2 LAST CDS_LIB mstr_discrete
J 0
(425 2375);
PAINT ORANGE (425 2375);
DISPLAY INVISIBLE (425 2375);
FORCEPROP 2 LAST CDS_LOCATION C6U14
J 0
(475 2475);
DISPLAY 0.617021 (475 2475);
PAINT AQUA (475 2475);
DISPLAY INVISIBLE (475 2475);
FORCEPROP 1 LAST PATH I25
J 0
(475 2525);
DISPLAY 0.978723 (475 2525);
PAINT WHITE (475 2525);
DISPLAY INVISIBLE (475 2525);
FORCEPROP 2 LAST ROOM VTT_GHJ_PWR_VR
J 0
(475 2525);
DISPLAY 1.021277 (475 2525);
PAINT ORANGE (475 2525);
DISPLAY INVISIBLE (475 2525);
FORCEPROP 2 LAST SEC_TYPE 0603LF
J 0
(481 2590);
DISPLAY 1.021277 (481 2590);
PAINT ORANGE (481 2590);
DISPLAY INVISIBLE (481 2590);
FORCEPROP 2 LAST BOM_COST MEM_VRD_VTT_GHJ
J 0
(475 2575);
DISPLAY 1.021277 (475 2575);
PAINT ORANGE (475 2575);
DISPLAY INVISIBLE (475 2575);
FORCEPROP 2 LAST SEC 1
J 0
(481 2590);
DISPLAY 0.680851 (481 2590);
PAINT MONO (481 2590);
DISPLAY INVISIBLE (481 2590);
FORCEADD GND..1
(425 2125);
FORCEPROP 3 LASTPIN (425 2175) SIG_NAME GND\g
J 0
(435 2185);
DISPLAY 0.659574 (435 2185);
PAINT MONO (435 2185);
DISPLAY INVISIBLE (435 2185);
FORCEPROP 2 LAST ROOM VTT_GHJ_PWR_VR
J 0
(-80 2205);
DISPLAY 1.021277 (-80 2205);
PAINT ORANGE (-80 2205);
DISPLAY INVISIBLE (-80 2205);
FORCEPROP 2 LAST BOM_COST MEM_VRD_VTT_GHJ
J 0
(-80 2255);
DISPLAY 1.021277 (-80 2255);
PAINT ORANGE (-80 2255);
DISPLAY INVISIBLE (-80 2255);
FORCEPROP 1 LAST BODY_TYPE PLUMBING
J 0
(380 2082);
DISPLAY 0.340426 (380 2082);
PAINT GREEN (380 2082);
DISPLAY INVISIBLE (380 2082);
FORCEPROP 1 LAST VOLTAGE 0.0V
J 0
(380 2082);
DISPLAY 0.340426 (380 2082);
PAINT SKYBLUE (380 2082);
DISPLAY INVISIBLE (380 2082);
FORCEPROP 1 LAST PATH I26
J 0
(500 2125);
DISPLAY 0.872340 (500 2125);
PAINT AQUA (500 2125);
DISPLAY INVISIBLE (500 2125);
FORCEPROP 2 LAST CDS_LIB mstr_symbols
J 0
(425 2125);
PAINT MONO (425 2125);
DISPLAY INVISIBLE (425 2125);
FORCEPROP 1 LAST SIZE 1B
J 0
(500 2075);
DISPLAY 0.893617 (500 2075);
PAINT GREEN (500 2075);
DISPLAY INVISIBLE (500 2075);
FORCEPROP 1 LAST HDL_POWER GND
J 0
(425 2275);
DISPLAY 0.893617 (425 2275);
PAINT GREEN (425 2275);
DISPLAY INVISIBLE (425 2275);
FORCEADD CAP..1
(425 1500);
FORCEPROP 1 LASTPIN (425 1400) $PN 2
J 0
(435 1380);
DISPLAY 0.617021 (435 1380);
PAINT WHITE (435 1380);
FORCEPROP 1 LASTPIN (425 1600) $PN 1
J 0
(435 1580);
DISPLAY 0.617021 (435 1580);
PAINT WHITE (435 1580);
FORCEPROP 1 LAST LOCATION C4G18
J 0
(475 1600);
DISPLAY 0.617021 (475 1600);
PAINT AQUA (475 1600);
FORCEPROP 1 LAST PART_NUMBER D97712-011
J 0
(475 1450);
DISPLAY 0.617021 (475 1450);
PAINT BLUE (475 1450);
FORCEPROP 1 LAST VALUE 1.0UF
J 0
(475 1550);
DISPLAY 0.617021 (475 1550);
PAINT SKYBLUE (475 1550);
FORCEPROP 1 LAST TOLERANCE 10%
J 0
(475 1500);
DISPLAY 0.617021 (475 1500);
PAINT SKYBLUE (475 1500);
FORCEPROP 1 LAST PACK_TYPE 0402
J 0
(475 1400);
DISPLAY 0.617021 (475 1400);
PAINT SKYBLUE (475 1400);
FORCEPROP 1 LAST VOLTAGE 16V
J 0
(625 1550);
DISPLAY 0.617021 (625 1550);
PAINT SKYBLUE (625 1550);
FORCEPROP 1 LAST MATERIAL X6S
J 0
(600 1500);
DISPLAY 0.617021 (600 1500);
PAINT SKYBLUE (600 1500);
FORCEPROP 2 LAST CDS_LIB mstr_discrete
J 0
(425 1500);
PAINT ORANGE (425 1500);
DISPLAY INVISIBLE (425 1500);
FORCEPROP 2 LAST CDS_LOCATION C4G18
J 0
(475 1600);
DISPLAY 0.617021 (475 1600);
PAINT AQUA (475 1600);
DISPLAY INVISIBLE (475 1600);
FORCEPROP 2 LAST ROOM VTT_GHJ_PWR_VR
J 0
(475 1650);
DISPLAY 1.021277 (475 1650);
PAINT ORANGE (475 1650);
DISPLAY INVISIBLE (475 1650);
FORCEPROP 1 LAST PATH I27
J 0
(475 1650);
DISPLAY 0.978723 (475 1650);
PAINT WHITE (475 1650);
DISPLAY INVISIBLE (475 1650);
FORCEPROP 2 LAST SEC 1
J 0
(475 1696);
DISPLAY 0.680851 (475 1696);
PAINT MONO (475 1696);
DISPLAY INVISIBLE (475 1696);
FORCEPROP 2 LAST BOM_COST MEM_VRD_VTT_GHJ
J 0
(475 1700);
DISPLAY 1.021277 (475 1700);
PAINT ORANGE (475 1700);
DISPLAY INVISIBLE (475 1700);
FORCEPROP 2 LAST SEC_TYPE 0402
J 0
(475 1696);
DISPLAY 1.021277 (475 1696);
PAINT ORANGE (475 1696);
DISPLAY INVISIBLE (475 1696);
FORCEADD GND..1
(425 1275);
FORCEPROP 3 LASTPIN (425 1325) SIG_NAME GND\g
J 0
(435 1335);
DISPLAY 0.659574 (435 1335);
PAINT MONO (435 1335);
DISPLAY INVISIBLE (435 1335);
FORCEPROP 1 LAST VOLTAGE 0.0V
J 0
(380 1232);
DISPLAY 0.340426 (380 1232);
PAINT SKYBLUE (380 1232);
DISPLAY INVISIBLE (380 1232);
FORCEPROP 1 LAST BODY_TYPE PLUMBING
J 0
(380 1232);
DISPLAY 0.340426 (380 1232);
PAINT GREEN (380 1232);
DISPLAY INVISIBLE (380 1232);
FORCEPROP 1 LAST SIZE 1B
J 0
(500 1225);
DISPLAY 0.893617 (500 1225);
PAINT GREEN (500 1225);
DISPLAY INVISIBLE (500 1225);
FORCEPROP 2 LAST CDS_LIB mstr_symbols
J 0
(425 1275);
DISPLAY 0.744681 (425 1275);
PAINT MONO (425 1275);
DISPLAY INVISIBLE (425 1275);
FORCEPROP 1 LAST PATH I28
J 0
(500 1275);
DISPLAY 0.872340 (500 1275);
PAINT AQUA (500 1275);
DISPLAY INVISIBLE (500 1275);
FORCEPROP 1 LAST HDL_POWER GND
J 0
(425 1425);
DISPLAY 0.893617 (425 1425);
PAINT GREEN (425 1425);
DISPLAY INVISIBLE (425 1425);
FORCEADD CAP..1
(0 2350);
FORCEPROP 1 LAST LOCATION C6U13
J 0
(50 2450);
DISPLAY 0.617021 (50 2450);
PAINT AQUA (50 2450);
FORCEPROP 1 LAST VALUE 10UF
J 0
(50 2400);
DISPLAY 0.617021 (50 2400);
PAINT SKYBLUE (50 2400);
FORCEPROP 1 LAST TOLERANCE 20%
J 0
(50 2300);
DISPLAY 0.617021 (50 2300);
PAINT SKYBLUE (50 2300);
FORCEPROP 1 LAST PACK_TYPE 0603LF
J 0
(50 2150);
DISPLAY 0.617021 (50 2150);
PAINT SKYBLUE (50 2150);
FORCEPROP 1 LAST VOLTAGE 4V
J 0
(50 2350);
DISPLAY 0.617021 (50 2350);
PAINT SKYBLUE (50 2350);
FORCEPROP 1 LAST MATERIAL X6S
J 0
(50 2250);
DISPLAY 0.617021 (50 2250);
PAINT SKYBLUE (50 2250);
FORCEPROP 1 LASTPIN (0 2250) $PN 2
J 0
(10 2230);
DISPLAY 0.617021 (10 2230);
PAINT WHITE (10 2230);
FORCEPROP 1 LASTPIN (0 2450) $PN 1
J 0
(10 2430);
DISPLAY 0.617021 (10 2430);
PAINT WHITE (10 2430);
FORCEPROP 1 LAST PART_NUMBER E15431-001
J 0
(50 2200);
DISPLAY 0.617021 (50 2200);
PAINT BLUE (50 2200);
FORCEPROP 2 LAST CDS_LIB mstr_discrete
J 0
(0 2350);
PAINT ORANGE (0 2350);
DISPLAY INVISIBLE (0 2350);
FORCEPROP 2 LAST CDS_LOCATION C6U13
J 0
(50 2450);
DISPLAY 0.617021 (50 2450);
PAINT AQUA (50 2450);
DISPLAY INVISIBLE (50 2450);
FORCEPROP 1 LAST PATH I29
J 0
(50 2500);
DISPLAY 0.978723 (50 2500);
PAINT WHITE (50 2500);
DISPLAY INVISIBLE (50 2500);
FORCEPROP 2 LAST ROOM VTT_GHJ_PWR_VR
J 0
(50 2500);
DISPLAY 1.021277 (50 2500);
PAINT ORANGE (50 2500);
DISPLAY INVISIBLE (50 2500);
FORCEPROP 2 LAST BOM_COST MEM_VRD_VTT_GHJ
J 0
(50 2550);
DISPLAY 1.021277 (50 2550);
PAINT ORANGE (50 2550);
DISPLAY INVISIBLE (50 2550);
FORCEPROP 2 LAST SEC_TYPE 0603LF
J 0
(56 2565);
DISPLAY 1.021277 (56 2565);
PAINT ORANGE (56 2565);
DISPLAY INVISIBLE (56 2565);
FORCEPROP 2 LAST SEC 1
J 0
(56 2565);
DISPLAY 0.680851 (56 2565);
PAINT MONO (56 2565);
DISPLAY INVISIBLE (56 2565);
FORCEADD PVTT_GHJ..1
(5500 1575);
FORCEPROP 3 LASTPIN (5500 1525) SIG_NAME PVTT_GHJ\g
J 0
(5510 1535);
DISPLAY 0.659574 (5510 1535);
PAINT MONO (5510 1535);
DISPLAY INVISIBLE (5510 1535);
FORCEPROP 1 LAST BODY_TYPE PLUMBING
J 0
(5455 1532);
DISPLAY 0.340426 (5455 1532);
PAINT GREEN (5455 1532);
DISPLAY INVISIBLE (5455 1532);
FORCEPROP 1 LAST VOLTAGE 0.6V
J 0
(5455 1532);
DISPLAY 0.340426 (5455 1532);
PAINT SKYBLUE (5455 1532);
DISPLAY INVISIBLE (5455 1532);
FORCEPROP 1 LAST HDL_POWER PVTT_GHJ
J 1
(5500 1625);
DISPLAY 0.872340 (5500 1625);
PAINT GREEN (5500 1625);
DISPLAY INVISIBLE (5500 1625);
FORCEPROP 1 LAST PATH I3
J 0
(5550 1600);
DISPLAY 0.872340 (5550 1600);
PAINT AQUA (5550 1600);
DISPLAY INVISIBLE (5550 1600);
FORCEPROP 2 LAST CDS_LIB mstr_symbols
J 0
(5500 1575);
PAINT ORANGE (5500 1575);
DISPLAY INVISIBLE (5500 1575);
FORCEADD GND..1
(0 2100);
FORCEPROP 3 LASTPIN (0 2150) SIG_NAME GND\g
J 0
(10 2160);
DISPLAY 0.659574 (10 2160);
PAINT MONO (10 2160);
DISPLAY INVISIBLE (10 2160);
FORCEPROP 2 LAST ROOM VTT_GHJ_PWR_VR
J 0
(-505 2180);
DISPLAY 1.021277 (-505 2180);
PAINT ORANGE (-505 2180);
DISPLAY INVISIBLE (-505 2180);
FORCEPROP 1 LAST BODY_TYPE PLUMBING
J 0
(-45 2057);
DISPLAY 0.340426 (-45 2057);
PAINT GREEN (-45 2057);
DISPLAY INVISIBLE (-45 2057);
FORCEPROP 2 LAST BOM_COST MEM_VRD_VTT_GHJ
J 0
(-505 2230);
DISPLAY 1.021277 (-505 2230);
PAINT ORANGE (-505 2230);
DISPLAY INVISIBLE (-505 2230);
FORCEPROP 1 LAST VOLTAGE 0.0V
J 0
(-45 2057);
DISPLAY 0.340426 (-45 2057);
PAINT SKYBLUE (-45 2057);
DISPLAY INVISIBLE (-45 2057);
FORCEPROP 2 LAST CDS_LIB mstr_symbols
J 0
(0 2100);
DISPLAY 0.744681 (0 2100);
PAINT MONO (0 2100);
DISPLAY INVISIBLE (0 2100);
FORCEPROP 1 LAST HDL_POWER GND
J 0
(0 2250);
DISPLAY 0.893617 (0 2250);
PAINT GREEN (0 2250);
DISPLAY INVISIBLE (0 2250);
FORCEPROP 1 LAST SIZE 1B
J 0
(75 2050);
DISPLAY 0.893617 (75 2050);
PAINT GREEN (75 2050);
DISPLAY INVISIBLE (75 2050);
FORCEPROP 1 LAST PATH I30
J 0
(75 2100);
DISPLAY 0.872340 (75 2100);
PAINT AQUA (75 2100);
DISPLAY INVISIBLE (75 2100);
FORCEADD RES..1
(100 1775);
FORCEPROP 1 LAST PART_NUMBER G21497-005
J 0
(-25 1725);
DISPLAY 0.617021 (-25 1725);
PAINT BLUE (-25 1725);
FORCEPROP 1 LAST VALUE 0.0
J 2
(75 1675);
DISPLAY 0.617021 (75 1675);
PAINT SKYBLUE (75 1675);
FORCEPROP 1 LAST WATTAGE 1/16W
J 2
(75 1625);
DISPLAY 0.617021 (75 1625);
PAINT SKYBLUE (75 1625);
FORCEPROP 1 LAST MATERIAL CHIP
J 0
(100 1625);
DISPLAY 0.617021 (100 1625);
PAINT SKYBLUE (100 1625);
FORCEPROP 1 LAST TOLERANCE 5%
J 0
(100 1675);
DISPLAY 0.617021 (100 1675);
PAINT SKYBLUE (100 1675);
FORCEPROP 1 LAST PACK_TYPE 0402
J 0
(25 1575);
DISPLAY 0.617021 (25 1575);
PAINT SKYBLUE (25 1575);
FORCEPROP 1 LASTPIN (0 1775) $PN 1
J 0
(12 1787);
DISPLAY 0.617021 (12 1787);
PAINT WHITE (12 1787);
FORCEPROP 1 LASTPIN (200 1775) $PN 2
J 0
(162 1787);
DISPLAY 0.617021 (162 1787);
PAINT WHITE (162 1787);
FORCEPROP 1 LAST LOCATION R6U7
J 0
(50 1825);
DISPLAY 0.617021 (50 1825);
PAINT AQUA (50 1825);
FORCEPROP 2 LAST CDS_LIB mstr_discrete
J 0
(100 1775);
DISPLAY 0.744681 (100 1775);
PAINT MONO (100 1775);
DISPLAY INVISIBLE (100 1775);
FORCEPROP 2 LAST BOM_COST MEM_VRD_VTT_GHJ
J 0
(60 1910);
DISPLAY 1.021277 (60 1910);
PAINT ORANGE (60 1910);
DISPLAY INVISIBLE (60 1910);
FORCEPROP 2 LAST SEC_TYPE 0402
J 0
(66 1975);
DISPLAY 1.021277 (66 1975);
PAINT ORANGE (66 1975);
DISPLAY INVISIBLE (66 1975);
FORCEPROP 2 LAST SEC 1
J 0
(66 1975);
DISPLAY 0.680851 (66 1975);
PAINT MONO (66 1975);
DISPLAY INVISIBLE (66 1975);
FORCEPROP 2 LAST CDS_LOCATION R6U7
J 0
(50 1825);
DISPLAY 0.617021 (50 1825);
PAINT AQUA (50 1825);
DISPLAY INVISIBLE (50 1825);
FORCEPROP 1 LAST PATH I32
J 0
(50 1925);
DISPLAY 0.978723 (50 1925);
PAINT WHITE (50 1925);
DISPLAY INVISIBLE (50 1925);
FORCEPROP 2 LAST ROOM VTT_GHJ_PWR_VR
J 0
(60 1860);
DISPLAY 1.021277 (60 1860);
PAINT ORANGE (60 1860);
DISPLAY INVISIBLE (60 1860);
FORCEADD RES..2
R 2
(-350 675);
FORCEPROP 1 LAST MATERIAL EMPTY
J 2
(-390 600);
DISPLAY 0.617021 (-390 600);
PAINT RED (-390 600);
FORCEPROP 1 LAST PART_NUMBER G21796-021
J 2
(-390 550);
DISPLAY 0.617021 (-390 550);
PAINT BLUE (-390 550);
FORCEPROP 1 LAST WATTAGE 1/16W
J 2
(-390 650);
DISPLAY 0.617021 (-390 650);
PAINT SKYBLUE (-390 650);
FORCEPROP 1 LAST PACK_TYPE 0402
J 2
(-390 500);
DISPLAY 0.617021 (-390 500);
PAINT SKYBLUE (-390 500);
FORCEPROP 1 LAST TOLERANCE 1%
J 2
(-395 700);
DISPLAY 0.617021 (-395 700);
PAINT SKYBLUE (-395 700);
FORCEPROP 1 LASTPIN (-350 575) $PN 2
J 2
(-355 585);
DISPLAY 0.617021 (-355 585);
PAINT WHITE (-355 585);
FORCEPROP 1 LASTPIN (-350 775) $PN 1
J 2
(-355 737);
DISPLAY 0.617021 (-355 737);
PAINT WHITE (-355 737);
FORCEPROP 1 LAST VALUE 1.0M
J 2
(-395 750);
DISPLAY 0.617021 (-395 750);
PAINT SKYBLUE (-395 750);
FORCEPROP 1 LAST LOCATION R6U3
J 2
(-395 800);
DISPLAY 0.617021 (-395 800);
PAINT AQUA (-395 800);
FORCEPROP 2 LAST CDS_LIB mstr_discrete
J 0
(-350 675);
PAINT ORANGE (-350 675);
DISPLAY INVISIBLE (-350 675);
FORCEPROP 2 LAST BOM_COST MEM_VRD_VTT_GHJ
J 0
(-385 890);
DISPLAY 1.021277 (-385 890);
PAINT ORANGE (-385 890);
DISPLAY INVISIBLE (-385 890);
FORCEPROP 2 LAST SEC_TYPE 0402
J 0
(-379 905);
DISPLAY 1.021277 (-379 905);
PAINT ORANGE (-379 905);
DISPLAY INVISIBLE (-379 905);
FORCEPROP 2 LAST SEC 1
J 0
(-379 905);
DISPLAY 0.680851 (-379 905);
PAINT MONO (-379 905);
DISPLAY INVISIBLE (-379 905);
FORCEPROP 2 LAST CDS_LOCATION R6U3
J 2
(-395 800);
DISPLAY 0.617021 (-395 800);
PAINT AQUA (-395 800);
DISPLAY INVISIBLE (-395 800);
FORCEPROP 1 LAST PATH I34
J 2
(-400 850);
DISPLAY 0.978723 (-400 850);
PAINT WHITE (-400 850);
DISPLAY INVISIBLE (-400 850);
FORCEPROP 2 LAST ROOM VTT_GHJ_PWR_VR
J 0
(-385 840);
DISPLAY 1.021277 (-385 840);
PAINT ORANGE (-385 840);
DISPLAY INVISIBLE (-385 840);
FORCEADD RES..1
(-575 150);
FORCEPROP 1 LAST PACK_TYPE 0402
J 0
(-650 -25);
DISPLAY 0.617021 (-650 -25);
PAINT SKYBLUE (-650 -25);
FORCEPROP 1 LAST MATERIAL CHIP
J 0
(-875 -25);
DISPLAY 0.617021 (-875 -25);
PAINT SKYBLUE (-875 -25);
FORCEPROP 1 LAST WATTAGE 1/16W
J 2
(-725 50);
DISPLAY 0.617021 (-725 50);
PAINT SKYBLUE (-725 50);
FORCEPROP 1 LASTPIN (-675 150) $PN 1
J 0
(-663 162);
DISPLAY 0.617021 (-663 162);
PAINT WHITE (-663 162);
FORCEPROP 1 LAST TOLERANCE 5%
J 0
(-575 50);
DISPLAY 0.617021 (-575 50);
PAINT SKYBLUE (-575 50);
FORCEPROP 1 LAST VALUE 0.0
J 2
(-600 50);
DISPLAY 0.617021 (-600 50);
PAINT SKYBLUE (-600 50);
FORCEPROP 1 LAST LOCATION R4G16
J 0
(-625 200);
DISPLAY 0.617021 (-625 200);
PAINT AQUA (-625 200);
FORCEPROP 1 LAST PART_NUMBER G21497-005
J 0
(-748 93);
DISPLAY 0.617021 (-748 93);
PAINT BLUE (-748 93);
FORCEPROP 1 LASTPIN (-475 150) $PN 2
J 0
(-513 162);
DISPLAY 0.617021 (-513 162);
PAINT WHITE (-513 162);
FORCEPROP 2 LAST CDS_LIB mstr_discrete
J 0
(-575 150);
PAINT ORANGE (-575 150);
DISPLAY INVISIBLE (-575 150);
FORCEPROP 2 LAST CDS_LOCATION R4G16
J 0
(-625 200);
DISPLAY 0.617021 (-625 200);
PAINT AQUA (-625 200);
DISPLAY INVISIBLE (-625 200);
FORCEPROP 2 LAST SEC 1
J 0
(-625 350);
DISPLAY 0.680851 (-625 350);
PAINT MONO (-625 350);
DISPLAY INVISIBLE (-625 350);
FORCEPROP 2 LAST SEC_TYPE 0402
J 0
(-625 350);
DISPLAY 1.021277 (-625 350);
PAINT ORANGE (-625 350);
DISPLAY INVISIBLE (-625 350);
FORCEPROP 2 LAST BOM_COST MEM_VRD_VTT_GHJ
J 0
(-605 355);
DISPLAY 1.021277 (-605 355);
PAINT ORANGE (-605 355);
DISPLAY INVISIBLE (-605 355);
FORCEPROP 1 LAST PATH I35
J 0
(-625 300);
DISPLAY 0.978723 (-625 300);
PAINT WHITE (-625 300);
DISPLAY INVISIBLE (-625 300);
FORCEPROP 2 LAST ROOM VTT_GHJ_PWR_VR
J 0
(-605 305);
DISPLAY 1.021277 (-605 305);
PAINT ORANGE (-605 305);
DISPLAY INVISIBLE (-605 305);
FORCEADD CAP..1
R 2
(-400 -375);
FORCEPROP 1 LAST MATERIAL EMPTY
J 2
(-454 -513);
DISPLAY 0.617021 (-454 -513);
PAINT RED (-454 -513);
FORCEPROP 1 LAST LOCATION C4G12
J 2
(-450 -275);
DISPLAY 0.617021 (-450 -275);
PAINT AQUA (-450 -275);
FORCEPROP 1 LAST VALUE 1000PF
J 2
(-450 -325);
DISPLAY 0.617021 (-450 -325);
PAINT SKYBLUE (-450 -325);
FORCEPROP 1 LAST TOLERANCE 10%
J 2
(-450 -425);
DISPLAY 0.617021 (-450 -425);
PAINT SKYBLUE (-450 -425);
FORCEPROP 1 LAST PACK_TYPE 0402LF
J 2
(-450 -469);
DISPLAY 0.617021 (-450 -469);
PAINT SKYBLUE (-450 -469);
FORCEPROP 1 LAST VOLTAGE 50V
J 2
(-450 -375);
DISPLAY 0.617021 (-450 -375);
PAINT SKYBLUE (-450 -375);
FORCEPROP 1 LASTPIN (-400 -475) $PN 2
J 2
(-410 -495);
DISPLAY 0.617021 (-410 -495);
PAINT WHITE (-410 -495);
FORCEPROP 1 LASTPIN (-400 -275) $PN 1
J 2
(-410 -295);
DISPLAY 0.617021 (-410 -295);
PAINT WHITE (-410 -295);
FORCEPROP 1 LAST PART_NUMBER A36096-046
J 2
(-450 -525);
DISPLAY 0.659574 (-450 -525);
PAINT BLUE (-450 -525);
DISPLAY INVISIBLE (-450 -525);
FORCEPROP 2 LAST CDS_LIB mstr_discrete
J 0
(-400 -375);
PAINT ORANGE (-400 -375);
DISPLAY INVISIBLE (-400 -375);
FORCEPROP 2 LAST CDS_LOCATION C4G12
J 2
(-450 -275);
DISPLAY 0.617021 (-450 -275);
PAINT AQUA (-450 -275);
DISPLAY INVISIBLE (-450 -275);
FORCEPROP 2 LAST SEC_TYPE 0402LF
J 0
(-429 -155);
DISPLAY 1.021277 (-429 -155);
PAINT ORANGE (-429 -155);
DISPLAY INVISIBLE (-429 -155);
FORCEPROP 2 LAST BOM_COST MEM_VRD_VTT_GHJ
J 0
(-435 -170);
DISPLAY 1.021277 (-435 -170);
PAINT ORANGE (-435 -170);
DISPLAY INVISIBLE (-435 -170);
FORCEPROP 2 LAST SEC 1
J 0
(-429 -155);
DISPLAY 0.680851 (-429 -155);
PAINT MONO (-429 -155);
DISPLAY INVISIBLE (-429 -155);
FORCEPROP 1 LAST PATH I36
J 2
(-450 -225);
DISPLAY 0.978723 (-450 -225);
PAINT WHITE (-450 -225);
DISPLAY INVISIBLE (-450 -225);
FORCEPROP 2 LAST ROOM VTT_GHJ_PWR_VR
J 0
(-435 -220);
DISPLAY 1.021277 (-435 -220);
PAINT ORANGE (-435 -220);
DISPLAY INVISIBLE (-435 -220);
FORCEADD GND..1
(-400 -600);
FORCEPROP 3 LASTPIN (-400 -550) SIG_NAME GND\g
J 0
(-390 -540);
DISPLAY 0.659574 (-390 -540);
PAINT MONO (-390 -540);
DISPLAY INVISIBLE (-390 -540);
FORCEPROP 1 LAST VOLTAGE 0.0V
J 0
(-445 -643);
DISPLAY 0.340426 (-445 -643);
PAINT SKYBLUE (-445 -643);
DISPLAY INVISIBLE (-445 -643);
FORCEPROP 2 LAST CDS_LIB mstr_symbols
J 0
(-400 -600);
PAINT MONO (-400 -600);
DISPLAY INVISIBLE (-400 -600);
FORCEPROP 1 LAST SIZE 1B
J 0
(-325 -650);
DISPLAY 0.893617 (-325 -650);
PAINT GREEN (-325 -650);
DISPLAY INVISIBLE (-325 -650);
FORCEPROP 1 LAST BODY_TYPE PLUMBING
J 0
(-445 -643);
DISPLAY 0.340426 (-445 -643);
PAINT GREEN (-445 -643);
DISPLAY INVISIBLE (-445 -643);
FORCEPROP 1 LAST PATH I37
J 0
(-325 -600);
DISPLAY 0.872340 (-325 -600);
PAINT AQUA (-325 -600);
DISPLAY INVISIBLE (-325 -600);
FORCEPROP 1 LAST HDL_POWER GND
J 0
(-400 -450);
DISPLAY 0.893617 (-400 -450);
PAINT GREEN (-400 -450);
DISPLAY INVISIBLE (-400 -450);
FORCEADD PVDDQ_GHJ..1
(-1475 2800);
FORCEPROP 3 LASTPIN (-1475 2750) SIG_NAME PVDDQ_GHJ\g
J 0
(-1465 2760);
DISPLAY 0.659574 (-1465 2760);
PAINT MONO (-1465 2760);
DISPLAY INVISIBLE (-1465 2760);
FORCEPROP 1 LAST HDL_POWER PVDDQ_GHJ
J 1
(-1475 2850);
DISPLAY 0.872340 (-1475 2850);
PAINT GREEN (-1475 2850);
DISPLAY INVISIBLE (-1475 2850);
FORCEPROP 1 LAST PATH I38
J 0
(-1425 2825);
DISPLAY 0.872340 (-1425 2825);
PAINT AQUA (-1425 2825);
DISPLAY INVISIBLE (-1425 2825);
FORCEPROP 1 LAST BODY_TYPE PLUMBING
J 0
(-1520 2757);
DISPLAY 0.340426 (-1520 2757);
PAINT GREEN (-1520 2757);
DISPLAY INVISIBLE (-1520 2757);
FORCEPROP 2 LAST CDS_LIB mstr_symbols
J 0
(-1475 2800);
PAINT ORANGE (-1475 2800);
DISPLAY INVISIBLE (-1475 2800);
FORCEPROP 1 LAST VOLTAGE 1.2V
J 0
(-1520 2757);
DISPLAY 0.340426 (-1520 2757);
PAINT SKYBLUE (-1520 2757);
DISPLAY INVISIBLE (-1520 2757);
FORCEADD RES..2
R 1
(-775 1575);
FORCEPROP 1 LAST PART_NUMBER G21497-005
J 0
(-875 1465);
DISPLAY 0.617021 (-875 1465);
PAINT BLUE (-875 1465);
FORCEPROP 1 LAST VALUE 0.0
J 0
(-850 1520);
DISPLAY 0.617021 (-850 1520);
PAINT SKYBLUE (-850 1520);
FORCEPROP 1 LAST TOLERANCE 5%
J 0
(-925 1520);
DISPLAY 0.617021 (-925 1520);
PAINT SKYBLUE (-925 1520);
FORCEPROP 1 LAST WATTAGE 1/16W
J 0
(-750 1515);
DISPLAY 0.617021 (-750 1515);
PAINT SKYBLUE (-750 1515);
FORCEPROP 1 LASTPIN (-875 1575) $PN 1
R 1
J 0
(-837 1580);
DISPLAY 0.617021 (-837 1580);
PAINT WHITE (-837 1580);
FORCEPROP 1 LAST LOCATION R6U6
J 0
(-825 1695);
DISPLAY 0.617021 (-825 1695);
PAINT AQUA (-825 1695);
FORCEPROP 1 LASTPIN (-675 1575) $PN 2
R 1
J 0
(-685 1580);
DISPLAY 0.617021 (-685 1580);
PAINT WHITE (-685 1580);
FORCEPROP 1 LAST PACK_TYPE 0402
J 0
(-550 1515);
DISPLAY 0.617021 (-550 1515);
PAINT SKYBLUE (-550 1515);
FORCEPROP 1 LAST MATERIAL CHIP
J 0
(-850 1340);
PAINT SKYBLUE (-850 1340);
DISPLAY INVISIBLE (-850 1340);
FORCEPROP 1 LAST PATH I39
R 1
J 0
(-950 1625);
DISPLAY 0.978723 (-950 1625);
PAINT WHITE (-950 1625);
DISPLAY INVISIBLE (-950 1625);
FORCEPROP 2 LAST CDS_LIB mstr_discrete
R 1
J 0
(-775 1575);
PAINT ORANGE (-775 1575);
DISPLAY INVISIBLE (-775 1575);
FORCEPROP 2 LAST BOM_COST MEM_VRD_VTT_GHJ
J 0
(-800 1725);
DISPLAY 1.021277 (-800 1725);
PAINT ORANGE (-800 1725);
DISPLAY INVISIBLE (-800 1725);
FORCEPROP 2 LAST SEC_TYPE 0402
J 0
(-794 1665);
DISPLAY 1.021277 (-794 1665);
PAINT ORANGE (-794 1665);
DISPLAY INVISIBLE (-794 1665);
FORCEPROP 2 LAST SEC 1
J 0
(-794 1665);
DISPLAY 0.680851 (-794 1665);
PAINT MONO (-794 1665);
DISPLAY INVISIBLE (-794 1665);
FORCEPROP 2 LAST CDS_LOCATION R6U6
J 0
(-825 1695);
DISPLAY 0.617021 (-825 1695);
PAINT AQUA (-825 1695);
DISPLAY INVISIBLE (-825 1695);
FORCEPROP 2 LAST NO_XNET_CONNECTION 1
J 0
(-825 1725);
PAINT MONO (-825 1725);
DISPLAY INVISIBLE (-825 1725);
FORCEPROP 2 LAST ROOM VTT_GHJ_PWR_VR
J 0
(-800 1675);
DISPLAY 1.021277 (-800 1675);
PAINT ORANGE (-800 1675);
DISPLAY INVISIBLE (-800 1675);
FORCEADD OFFPAGE..1
(-1450 150);
FORCEPROP 2 LAST $XR0 223 
J 0
(-1702 150);
DISPLAY 0.638298 (-1702 150);
PAINT MONO (-1702 150);
FORCEPROP 2 LAST PATH I41
J 0
(-1729 202);
DISPLAY 1.021277 (-1729 202);
PAINT ORANGE (-1729 202);
DISPLAY INVISIBLE (-1729 202);
FORCEPROP 1 LAST COMMENT_BODY TRUE
J 0
(-1325 50);
DISPLAY 0.872340 (-1325 50);
PAINT GREEN (-1325 50);
DISPLAY INVISIBLE (-1325 50);
FORCEPROP 1 LAST OFFPAGE TRUE
J 0
(-1125 25);
DISPLAY 0.872340 (-1125 25);
PAINT GREEN (-1125 25);
DISPLAY INVISIBLE (-1125 25);
FORCEPROP 2 LAST CDS_LIB mstr_standard
J 0
(-1450 150);
DISPLAY 0.744681 (-1450 150);
PAINT MONO (-1450 150);
DISPLAY INVISIBLE (-1450 150);
FORCEADD P3V3..1
(-525 2075);
FORCEPROP 3 LASTPIN (-525 2025) SIG_NAME P3V3\g
J 0
(-515 2035);
DISPLAY 0.659574 (-515 2035);
PAINT MONO (-515 2035);
DISPLAY INVISIBLE (-515 2035);
FORCEPROP 1 LAST HDL_POWER P3V3
J 0
(-850 1950);
DISPLAY 0.872340 (-850 1950);
PAINT ORANGE (-850 1950);
DISPLAY INVISIBLE (-850 1950);
FORCEPROP 1 LAST BODY_TYPE PLUMBING
J 0
(-570 2032);
DISPLAY 0.340426 (-570 2032);
PAINT GREEN (-570 2032);
DISPLAY INVISIBLE (-570 2032);
FORCEPROP 1 LAST VOLTAGE 3.3V
J 0
(-570 2032);
DISPLAY 0.340426 (-570 2032);
PAINT SKYBLUE (-570 2032);
DISPLAY INVISIBLE (-570 2032);
FORCEPROP 1 LAST SIZE 1B
J 0
(-480 2097);
DISPLAY 0.340426 (-480 2097);
PAINT GREEN (-480 2097);
DISPLAY INVISIBLE (-480 2097);
FORCEPROP 2 LAST CDS_LIB mstr_symbols
J 0
(-525 2075);
PAINT ORANGE (-525 2075);
DISPLAY INVISIBLE (-525 2075);
FORCEPROP 1 LAST PATH I42
J 0
(-480 2077);
DISPLAY 0.340426 (-480 2077);
PAINT GREEN (-480 2077);
DISPLAY INVISIBLE (-480 2077);
FORCEADD P3V3..1
(3450 2275);
FORCEPROP 3 LASTPIN (3450 2225) SIG_NAME P3V3\g
J 0
(3460 2235);
DISPLAY 0.659574 (3460 2235);
PAINT MONO (3460 2235);
DISPLAY INVISIBLE (3460 2235);
FORCEPROP 1 LAST HDL_POWER P3V3
J 0
(3125 2150);
DISPLAY 0.872340 (3125 2150);
PAINT ORANGE (3125 2150);
DISPLAY INVISIBLE (3125 2150);
FORCEPROP 1 LAST BODY_TYPE PLUMBING
J 0
(3405 2232);
DISPLAY 0.340426 (3405 2232);
PAINT GREEN (3405 2232);
DISPLAY INVISIBLE (3405 2232);
FORCEPROP 1 LAST VOLTAGE 3.3V
J 0
(3405 2232);
DISPLAY 0.340426 (3405 2232);
PAINT SKYBLUE (3405 2232);
DISPLAY INVISIBLE (3405 2232);
FORCEPROP 1 LAST PATH I43
J 0
(3495 2277);
DISPLAY 0.340426 (3495 2277);
PAINT GREEN (3495 2277);
DISPLAY INVISIBLE (3495 2277);
FORCEPROP 1 LAST SIZE 1B
J 0
(3495 2297);
DISPLAY 0.340426 (3495 2297);
PAINT GREEN (3495 2297);
DISPLAY INVISIBLE (3495 2297);
FORCEPROP 2 LAST CDS_LIB mstr_symbols
J 0
(3450 2275);
PAINT ORANGE (3450 2275);
DISPLAY INVISIBLE (3450 2275);
FORCEADD GND..1
(275 775);
FORCEPROP 3 LASTPIN (275 825) SIG_NAME GND\g
J 0
(285 835);
DISPLAY 0.659574 (285 835);
PAINT MONO (285 835);
DISPLAY INVISIBLE (285 835);
FORCEPROP 1 LAST VOLTAGE 0.0V
J 0
(230 732);
DISPLAY 0.340426 (230 732);
PAINT SKYBLUE (230 732);
DISPLAY INVISIBLE (230 732);
FORCEPROP 1 LAST BODY_TYPE PLUMBING
J 0
(230 732);
DISPLAY 0.340426 (230 732);
PAINT GREEN (230 732);
DISPLAY INVISIBLE (230 732);
FORCEPROP 1 LAST SIZE 1B
J 0
(350 725);
DISPLAY 0.872340 (350 725);
PAINT AQUA (350 725);
DISPLAY INVISIBLE (350 725);
FORCEPROP 2 LAST CDS_LIB mstr_symbols
J 0
(275 775);
PAINT ORANGE (275 775);
DISPLAY INVISIBLE (275 775);
FORCEPROP 1 LAST PATH I45
J 0
(350 775);
DISPLAY 0.872340 (350 775);
PAINT AQUA (350 775);
DISPLAY INVISIBLE (350 775);
FORCEPROP 1 LAST HDL_POWER GND
J 0
(275 925);
DISPLAY 0.872340 (275 925);
PAINT GREEN (275 925);
DISPLAY INVISIBLE (275 925);
FORCEADD CAP..1
(275 1000);
FORCEPROP 1 LASTPIN (275 900) $PN 2
J 0
(285 880);
DISPLAY 0.617021 (285 880);
PAINT ORANGE (285 880);
FORCEPROP 1 LAST PACK_TYPE 0603
J 0
(325 800);
DISPLAY 0.617021 (325 800);
PAINT SKYBLUE (325 800);
FORCEPROP 1 LAST TOLERANCE 10%
J 0
(325 950);
DISPLAY 0.617021 (325 950);
PAINT SKYBLUE (325 950);
FORCEPROP 1 LAST MATERIAL X6S
J 0
(325 900);
DISPLAY 0.617021 (325 900);
PAINT SKYBLUE (325 900);
FORCEPROP 1 LAST PART_NUMBER E15431-003
J 0
(325 850);
DISPLAY 0.617021 (325 850);
PAINT BLUE (325 850);
FORCEPROP 1 LAST VOLTAGE 6.3V
J 0
(325 1000);
DISPLAY 0.617021 (325 1000);
PAINT SKYBLUE (325 1000);
FORCEPROP 1 LASTPIN (275 1100) $PN 1
J 0
(285 1080);
DISPLAY 0.617021 (285 1080);
PAINT ORANGE (285 1080);
FORCEPROP 1 LAST VALUE 4.7UF
J 0
(325 1050);
DISPLAY 0.617021 (325 1050);
PAINT SKYBLUE (325 1050);
FORCEPROP 1 LAST LOCATION C6U11
J 0
(325 1100);
DISPLAY 0.617021 (325 1100);
PAINT AQUA (325 1100);
FORCEPROP 2 LAST CDS_LIB mstr_discrete
J 0
(275 1000);
PAINT ORANGE (275 1000);
DISPLAY INVISIBLE (275 1000);
FORCEPROP 2 LAST CDS_LOCATION C6U11
J 0
(325 1100);
DISPLAY 0.617021 (325 1100);
PAINT AQUA (325 1100);
DISPLAY INVISIBLE (325 1100);
FORCEPROP 1 LAST PATH I46
J 0
(325 1150);
DISPLAY 0.978723 (325 1150);
PAINT WHITE (325 1150);
DISPLAY INVISIBLE (325 1150);
FORCEPROP 2 LAST SEC_TYPE 0603
J 0
(325 1200);
DISPLAY 1.021277 (325 1200);
PAINT ORANGE (325 1200);
DISPLAY INVISIBLE (325 1200);
FORCEPROP 2 LAST SEC 1
J 0
(325 1200);
DISPLAY 0.680851 (325 1200);
PAINT MONO (325 1200);
DISPLAY INVISIBLE (325 1200);
FORCEPROP 0 LAST ROOM VTT_GHJ_PWR_VR
J 0
(325 1200);
DISPLAY 1.021277 (325 1200);
PAINT ORANGE (325 1200);
DISPLAY INVISIBLE (325 1200);
FORCEADD CAP_A..1
(3475 3375);
FORCEPROP 1 LASTPIN (3475 3275) $PN 2
J 0
(3485 3255);
DISPLAY 0.617021 (3485 3255);
PAINT ORANGE (3485 3255);
FORCEPROP 1 LAST VOLTAGE 4V
J 0
(3525 3375);
DISPLAY 0.617021 (3525 3375);
PAINT SKYBLUE (3525 3375);
FORCEPROP 1 LASTPIN (3475 3475) $PN 1
J 0
(3485 3455);
DISPLAY 0.617021 (3485 3455);
PAINT ORANGE (3485 3455);
FORCEPROP 1 LAST LOCATION C2F2
J 0
(3525 3475);
DISPLAY 0.617021 (3525 3475);
PAINT AQUA (3525 3475);
FORCEPROP 1 LAST PART_NUMBER 602433-106
J 0
(3525 3225);
DISPLAY 0.617021 (3525 3225);
PAINT BLUE (3525 3225);
FORCEPROP 1 LAST VALUE 47UF
J 0
(3525 3425);
DISPLAY 0.617021 (3525 3425);
PAINT SKYBLUE (3525 3425);
FORCEPROP 1 LAST TOLERANCE 20%
J 0
(3525 3325);
DISPLAY 0.617021 (3525 3325);
PAINT SKYBLUE (3525 3325);
FORCEPROP 1 LAST PACK_TYPE 0603V
J 0
(3525 3175);
DISPLAY 0.617021 (3525 3175);
PAINT SKYBLUE (3525 3175);
FORCEPROP 1 LAST MATERIAL X5R
J 0
(3525 3275);
DISPLAY 0.617021 (3525 3275);
PAINT SKYBLUE (3525 3275);
FORCEPROP 2 LAST CDS_LIB dev_discrete
J 0
(3475 3375);
PAINT ORANGE (3475 3375);
DISPLAY INVISIBLE (3475 3375);
FORCEPROP 2 LAST CDS_LOCATION C2F2
J 0
(3525 3475);
DISPLAY 0.617021 (3525 3475);
PAINT AQUA (3525 3475);
DISPLAY INVISIBLE (3525 3475);
FORCEPROP 2 LAST CDS_SEC 1
J 0
(3525 3525);
PAINT ORANGE (3525 3525);
DISPLAY INVISIBLE (3525 3525);
FORCEPROP 1 LAST PATH I47
J 0
(3525 3525);
DISPLAY 0.978723 (3525 3525);
PAINT WHITE (3525 3525);
DISPLAY INVISIBLE (3525 3525);
FORCEPROP 2 LAST SEC_TYPE 0603V
J 0
(3525 3575);
DISPLAY 1.021277 (3525 3575);
PAINT ORANGE (3525 3575);
DISPLAY INVISIBLE (3525 3575);
FORCEPROP 2 LAST SEC 1
J 0
(3525 3575);
DISPLAY 0.680851 (3525 3575);
PAINT MONO (3525 3575);
DISPLAY INVISIBLE (3525 3575);
FORCEADD CAP_A..1
(3825 3375);
FORCEPROP 1 LASTPIN (3825 3475) $PN 1
J 0
(3835 3455);
DISPLAY 0.617021 (3835 3455);
PAINT ORANGE (3835 3455);
FORCEPROP 1 LASTPIN (3825 3275) $PN 2
J 0
(3835 3255);
DISPLAY 0.617021 (3835 3255);
PAINT ORANGE (3835 3255);
FORCEPROP 1 LAST MATERIAL X5R
J 0
(3875 3275);
DISPLAY 0.617021 (3875 3275);
PAINT SKYBLUE (3875 3275);
FORCEPROP 1 LAST LOCATION C8T3
J 0
(3875 3475);
DISPLAY 0.617021 (3875 3475);
PAINT AQUA (3875 3475);
FORCEPROP 1 LAST VALUE 47UF
J 0
(3875 3425);
DISPLAY 0.617021 (3875 3425);
PAINT SKYBLUE (3875 3425);
FORCEPROP 1 LAST TOLERANCE 20%
J 0
(3875 3325);
DISPLAY 0.617021 (3875 3325);
PAINT SKYBLUE (3875 3325);
FORCEPROP 1 LAST PACK_TYPE 0603V
J 0
(3875 3175);
DISPLAY 0.617021 (3875 3175);
PAINT SKYBLUE (3875 3175);
FORCEPROP 1 LAST VOLTAGE 4V
J 0
(3875 3375);
DISPLAY 0.617021 (3875 3375);
PAINT SKYBLUE (3875 3375);
FORCEPROP 1 LAST PART_NUMBER 602433-106
J 0
(3875 3225);
DISPLAY 0.617021 (3875 3225);
PAINT BLUE (3875 3225);
FORCEPROP 2 LAST CDS_LIB dev_discrete
J 0
(3825 3375);
PAINT ORANGE (3825 3375);
DISPLAY INVISIBLE (3825 3375);
FORCEPROP 2 LAST CDS_LOCATION C8T3
J 0
(3875 3475);
DISPLAY 0.617021 (3875 3475);
PAINT AQUA (3875 3475);
DISPLAY INVISIBLE (3875 3475);
FORCEPROP 2 LAST CDS_SEC 1
J 0
(3875 3525);
PAINT ORANGE (3875 3525);
DISPLAY INVISIBLE (3875 3525);
FORCEPROP 1 LAST PATH I48
J 0
(3875 3525);
DISPLAY 0.978723 (3875 3525);
PAINT WHITE (3875 3525);
DISPLAY INVISIBLE (3875 3525);
FORCEPROP 2 LAST SEC_TYPE 0603V
J 0
(3875 3575);
DISPLAY 1.021277 (3875 3575);
PAINT ORANGE (3875 3575);
DISPLAY INVISIBLE (3875 3575);
FORCEPROP 2 LAST SEC 1
J 0
(3875 3575);
DISPLAY 0.680851 (3875 3575);
PAINT MONO (3875 3575);
DISPLAY INVISIBLE (3875 3575);
FORCEADD CAP_A..1
(4225 3375);
FORCEPROP 1 LASTPIN (4225 3275) $PN 2
J 0
(4235 3255);
DISPLAY 0.617021 (4235 3255);
PAINT ORANGE (4235 3255);
FORCEPROP 1 LASTPIN (4225 3475) $PN 1
J 0
(4235 3455);
DISPLAY 0.617021 (4235 3455);
PAINT ORANGE (4235 3455);
FORCEPROP 1 LAST VOLTAGE 4V
J 0
(4275 3375);
DISPLAY 0.617021 (4275 3375);
PAINT SKYBLUE (4275 3375);
FORCEPROP 1 LAST LOCATION C8U10
J 0
(4275 3475);
DISPLAY 0.617021 (4275 3475);
PAINT AQUA (4275 3475);
FORCEPROP 1 LAST PART_NUMBER 602433-106
J 0
(4275 3225);
DISPLAY 0.617021 (4275 3225);
PAINT BLUE (4275 3225);
FORCEPROP 1 LAST VALUE 47UF
J 0
(4275 3425);
DISPLAY 0.617021 (4275 3425);
PAINT SKYBLUE (4275 3425);
FORCEPROP 1 LAST TOLERANCE 20%
J 0
(4275 3325);
DISPLAY 0.617021 (4275 3325);
PAINT SKYBLUE (4275 3325);
FORCEPROP 1 LAST PACK_TYPE 0603V
J 0
(4275 3175);
DISPLAY 0.617021 (4275 3175);
PAINT SKYBLUE (4275 3175);
FORCEPROP 1 LAST MATERIAL X5R
J 0
(4275 3275);
DISPLAY 0.617021 (4275 3275);
PAINT SKYBLUE (4275 3275);
FORCEPROP 2 LAST CDS_LOCATION C8U10
J 0
(4275 3475);
DISPLAY 0.617021 (4275 3475);
PAINT AQUA (4275 3475);
DISPLAY INVISIBLE (4275 3475);
FORCEPROP 2 LAST CDS_LIB dev_discrete
J 0
(4225 3375);
PAINT ORANGE (4225 3375);
DISPLAY INVISIBLE (4225 3375);
FORCEPROP 2 LAST CDS_SEC 1
J 0
(4275 3525);
PAINT ORANGE (4275 3525);
DISPLAY INVISIBLE (4275 3525);
FORCEPROP 1 LAST PATH I49
J 0
(4275 3525);
DISPLAY 0.978723 (4275 3525);
PAINT WHITE (4275 3525);
DISPLAY INVISIBLE (4275 3525);
FORCEPROP 2 LAST SEC_TYPE 0603V
J 0
(4275 3575);
DISPLAY 1.021277 (4275 3575);
PAINT ORANGE (4275 3575);
DISPLAY INVISIBLE (4275 3575);
FORCEPROP 2 LAST SEC 1
J 0
(4275 3575);
DISPLAY 0.680851 (4275 3575);
PAINT MONO (4275 3575);
DISPLAY INVISIBLE (4275 3575);
FORCEADD RES..1
(4025 1825);
FORCEPROP 1 LAST WATTAGE 1/16W
J 2
(4000 1675);
DISPLAY 0.617021 (4000 1675);
PAINT SKYBLUE (4000 1675);
FORCEPROP 1 LAST TOLERANCE 1%
J 0
(4025 1725);
DISPLAY 0.617021 (4025 1725);
PAINT SKYBLUE (4025 1725);
FORCEPROP 1 LAST VALUE 33.2
J 2
(4000 1725);
DISPLAY 0.617021 (4000 1725);
PAINT SKYBLUE (4000 1725);
FORCEPROP 1 LASTPIN (3925 1825) $PN 1
J 0
(3937 1837);
DISPLAY 0.617021 (3937 1837);
PAINT ORANGE (3937 1837);
FORCEPROP 1 LAST LOCATION R4G15
J 0
(3975 1875);
DISPLAY 0.617021 (3975 1875);
PAINT AQUA (3975 1875);
FORCEPROP 1 LAST PART_NUMBER G21796-074
J 0
(3975 1925);
DISPLAY 0.617021 (3975 1925);
PAINT BLUE (3975 1925);
FORCEPROP 1 LAST MATERIAL CHIP
J 0
(4025 1675);
DISPLAY 0.617021 (4025 1675);
PAINT SKYBLUE (4025 1675);
FORCEPROP 1 LASTPIN (4125 1825) $PN 2
J 0
(4087 1837);
DISPLAY 0.617021 (4087 1837);
PAINT ORANGE (4087 1837);
FORCEPROP 1 LAST PACK_TYPE 0402
J 0
(4275 1675);
DISPLAY 0.617021 (4275 1675);
PAINT SKYBLUE (4275 1675);
FORCEPROP 1 LAST PATH I51
J 0
(3975 1975);
DISPLAY 0.978723 (3975 1975);
PAINT WHITE (3975 1975);
DISPLAY INVISIBLE (3975 1975);
FORCEPROP 2 LAST CDS_LOCATION R4G15
J 0
(3975 1875);
DISPLAY 0.617021 (3975 1875);
PAINT AQUA (3975 1875);
DISPLAY INVISIBLE (3975 1875);
FORCEPROP 2 LAST CDS_LIB mstr_discrete
J 0
(4025 1825);
PAINT MONO (4025 1825);
DISPLAY INVISIBLE (4025 1825);
FORCEPROP 2 LAST SEC_TYPE 0402
J 0
(3975 2025);
DISPLAY 1.021277 (3975 2025);
PAINT ORANGE (3975 2025);
DISPLAY INVISIBLE (3975 2025);
FORCEPROP 2 LAST SEC 1
J 0
(3975 2025);
DISPLAY 0.680851 (3975 2025);
PAINT MONO (3975 2025);
DISPLAY INVISIBLE (3975 2025);
FORCEADD RES..1
R 1
(4775 1000);
FORCEPROP 1 LAST VALUE 51.1
R 1
J 2
(4875 975);
DISPLAY 0.617021 (4875 975);
PAINT SKYBLUE (4875 975);
FORCEPROP 1 LAST WATTAGE 1/16W
R 1
J 2
(4925 975);
DISPLAY 0.617021 (4925 975);
PAINT SKYBLUE (4925 975);
FORCEPROP 1 LAST LOCATION R6U8
R 1
J 0
(4725 950);
DISPLAY 0.617021 (4725 950);
PAINT AQUA (4725 950);
FORCEPROP 1 LAST PART_NUMBER G21796-208
R 1
J 0
(4675 950);
DISPLAY 0.617021 (4675 950);
PAINT BLUE (4675 950);
FORCEPROP 1 LAST TOLERANCE 1.0%
R 1
J 0
(4875 1000);
DISPLAY 0.617021 (4875 1000);
PAINT SKYBLUE (4875 1000);
FORCEPROP 1 LAST MATERIAL CHIP
R 1
J 0
(4925 1000);
DISPLAY 0.617021 (4925 1000);
PAINT SKYBLUE (4925 1000);
FORCEPROP 1 LAST PACK_TYPE 0402
R 1
J 0
(4925 1150);
DISPLAY 0.617021 (4925 1150);
PAINT SKYBLUE (4925 1150);
FORCEPROP 1 LAST PATH I52
R 1
J 0
(4625 950);
DISPLAY 0.978723 (4625 950);
PAINT WHITE (4625 950);
DISPLAY INVISIBLE (4625 950);
FORCEPROP 1 LASTPIN (4775 900) $PN 1
R 1
J 0
(4763 912);
DISPLAY 0.787234 (4763 912);
PAINT ORANGE (4763 912);
DISPLAY INVISIBLE (4763 912);
FORCEPROP 2 LAST CDS_LOCATION R6U8
R 1
J 0
(4725 950);
DISPLAY 0.617021 (4725 950);
PAINT AQUA (4725 950);
DISPLAY INVISIBLE (4725 950);
FORCEPROP 2 LAST CDS_LIB mstr_discrete
J 0
(4775 1000);
PAINT ORANGE (4775 1000);
DISPLAY INVISIBLE (4775 1000);
FORCEPROP 2 LAST CDS_SEC 1
J 0
(4800 1125);
PAINT MONO (4800 1125);
DISPLAY INVISIBLE (4800 1125);
FORCEPROP 2 LAST $SEC 1
J 0
(4800 1125);
PAINT MONO (4800 1125);
DISPLAY INVISIBLE (4800 1125);
FORCEPROP 1 LASTPIN (4775 1100) $PN 2
R 1
J 0
(4763 1062);
DISPLAY 0.787234 (4763 1062);
PAINT ORANGE (4763 1062);
DISPLAY INVISIBLE (4763 1062);
FORCEADD SHUNT..1
(4925 25);
FORCEPROP 1 LAST PART_NUMBER N_A
J 0
(4850 -65);
DISPLAY 0.617021 (4850 -65);
PAINT BLUE (4850 -65);
FORCEPROP 1 LASTPIN (4775 25) $PN 1
J 2
(4825 35);
DISPLAY 0.617021 (4825 35);
PAINT ORANGE (4825 35);
FORCEPROP 1 LAST LOCATION SH8U1
J 0
(4850 75);
DISPLAY 0.617021 (4850 75);
PAINT AQUA (4850 75);
FORCEPROP 1 LASTPIN (5075 25) $PN 2
J 0
(5035 35);
DISPLAY 0.617021 (5035 35);
PAINT ORANGE (5035 35);
FORCEPROP 1 LAST MATERIAL EMPTY
J 0
(4850 -110);
DISPLAY 0.978723 (4850 -110);
PAINT RED (4850 -110);
DISPLAY INVISIBLE (4850 -110);
FORCEPROP 1 LAST PIN_SHORT A:B
J 0
(4850 -225);
DISPLAY 1.021277 (4850 -225);
PAINT ORANGE (4850 -225);
DISPLAY INVISIBLE (4850 -225);
FORCEPROP 1 LAST PACK_TYPE SH0201
J 0
(4865 -160);
DISPLAY 0.978723 (4865 -160);
PAINT SKYBLUE (4865 -160);
DISPLAY INVISIBLE (4865 -160);
FORCEPROP 0 LAST SEC 1
J 0
(4850 125);
DISPLAY 0.680851 (4850 125);
PAINT MONO (4850 125);
DISPLAY INVISIBLE (4850 125);
FORCEPROP 2 LAST CDS_LIB mstr_misc
J 0
(4925 25);
PAINT ORANGE (4925 25);
DISPLAY INVISIBLE (4925 25);
FORCEPROP 1 LAST PATH I53
J 0
(4875 125);
DISPLAY 0.978723 (4875 125);
PAINT ORANGE (4875 125);
DISPLAY INVISIBLE (4875 125);
FORCEPROP 2 LAST SEC_TYPE SH0201
J 0
(4875 175);
DISPLAY 1.021277 (4875 175);
PAINT ORANGE (4875 175);
DISPLAY INVISIBLE (4875 175);
FORCEADD GND..1
(4350 3025);
FORCEPROP 3 LASTPIN (4350 3075) SIG_NAME GND\g
J 0
(4360 3085);
DISPLAY 0.659574 (4360 3085);
PAINT MONO (4360 3085);
DISPLAY INVISIBLE (4360 3085);
FORCEPROP 2 LAST ROOM VTT_GHJ_VR
J 0
(3800 3100);
PAINT ORANGE (3800 3100);
DISPLAY INVISIBLE (3800 3100);
FORCEPROP 2 LAST BOM_COST MEM_VRD_PVDDQ_GHJ
J 0
(4025 3100);
PAINT MONO (4025 3100);
DISPLAY INVISIBLE (4025 3100);
FORCEPROP 1 LAST VOLTAGE 0.0V
J 0
(4305 2982);
DISPLAY 0.340426 (4305 2982);
PAINT SKYBLUE (4305 2982);
DISPLAY INVISIBLE (4305 2982);
FORCEPROP 2 LAST CDS_LIB mstr_symbols
J 0
(4350 3025);
PAINT ORANGE (4350 3025);
DISPLAY INVISIBLE (4350 3025);
FORCEPROP 1 LAST SIZE 1B
J 0
(4425 2975);
DISPLAY 0.893617 (4425 2975);
PAINT GREEN (4425 2975);
DISPLAY INVISIBLE (4425 2975);
FORCEPROP 1 LAST BODY_TYPE PLUMBING
J 0
(4305 2982);
DISPLAY 0.340426 (4305 2982);
PAINT GREEN (4305 2982);
DISPLAY INVISIBLE (4305 2982);
FORCEPROP 1 LAST PATH I7
J 0
(4425 3025);
DISPLAY 0.872340 (4425 3025);
PAINT AQUA (4425 3025);
DISPLAY INVISIBLE (4425 3025);
FORCEPROP 1 LAST HDL_POWER GND
J 0
(4350 3175);
DISPLAY 0.893617 (4350 3175);
PAINT GREEN (4350 3175);
DISPLAY INVISIBLE (4350 3175);
FORCEADD CAD_NOTE..1
(75 2750);
FORCEPROP 0 LAST L1 PLACE CLOSE TO CONTROLLER
J 0
(-12 2658);
DISPLAY 0.617021 (-12 2658);
PAINT WHITE (-12 2658);
FORCEPROP 2 LAST CDS_LIB mstr_symbols
J 0
(75 2750);
PAINT ORANGE (75 2750);
DISPLAY INVISIBLE (75 2750);
FORCEPROP 1 LAST COMMENT_BODY TRUE
J 0
(100 2850);
DISPLAY 0.978723 (100 2850);
PAINT ORANGE (100 2850);
DISPLAY INVISIBLE (100 2850);
FORCEADD CAD_NOTE..1
(2225 1575);
FORCEPROP 0 LAST L1 PLACE CLOSE TO CONTROLLER
J 0
(2043 1483);
DISPLAY 0.617021 (2043 1483);
PAINT WHITE (2043 1483);
FORCEPROP 2 LAST CDS_LIB mstr_symbols
J 0
(2225 1575);
PAINT ORANGE (2225 1575);
DISPLAY INVISIBLE (2225 1575);
FORCEPROP 1 LAST COMMENT_BODY TRUE
J 0
(2250 1675);
DISPLAY 0.978723 (2250 1675);
PAINT ORANGE (2250 1675);
DISPLAY INVISIBLE (2250 1675);
FORCEADD CAD_NOTE..1
(4775 225);
FORCEPROP 0 LAST L1 SPOF
J 0
(4636 76);
DISPLAY 0.617021 (4636 76);
PAINT WHITE (4636 76);
FORCEPROP 2 LAST CDS_LIB mstr_symbols
J 0
(4775 225);
PAINT ORANGE (4775 225);
DISPLAY INVISIBLE (4775 225);
FORCEPROP 1 LAST COMMENT_BODY TRUE
J 0
(4800 325);
DISPLAY 0.978723 (4800 325);
PAINT ORANGE (4800 325);
DISPLAY INVISIBLE (4800 325);
FORCEADD PRELIM..6
(1510 1065);
PAINT GRAY (1510 1065);
FORCEPROP 2 LAST CDS_LIB mstr_misc
J 0
(1510 1065);
PAINT ORANGE (1510 1065);
DISPLAY INVISIBLE (1510 1065);
FORCEPROP 1 LAST COMMENT_BODY TRUE
J 0
(1510 1065);
PAINT ORANGE (1510 1065);
DISPLAY INVISIBLE (1510 1065);
FORCEADD CAD_NOTE..1
(4775 3650);
FORCEPROP 2 LAST CDS_LIB mstr_symbols
J 0
(4775 3650);
PAINT ORANGE (4775 3650);
DISPLAY INVISIBLE (4775 3650);
FORCEPROP 1 LAST COMMENT_BODY TRUE
J 0
(4800 3750);
DISPLAY 0.978723 (4800 3750);
PAINT ORANGE (4800 3750);
DISPLAY INVISIBLE (4800 3750);
FORCEADD DNS..2
(-345 670);
PAINT RED (-345 670);
FORCEPROP 1 LAST COMMENT_BODY TRUE
R 1
J 0
(-270 445);
DISPLAY 0.872340 (-270 445);
PAINT GREEN (-270 445);
DISPLAY INVISIBLE (-270 445);
FORCEPROP 2 LAST CDS_LIB mstr_misc
J 0
(-345 670);
PAINT ORANGE (-345 670);
DISPLAY INVISIBLE (-345 670);
FORCEADD CAD_NOTE..1
(4700 -250);
FORCEPROP 0 LAST L2 OF PVTT PLANE
J 0
(4582 -397);
DISPLAY 0.617021 (4582 -397);
PAINT WHITE (4582 -397);
FORCEPROP 0 LAST L1 PLACE NEAR CENTER
J 0
(4582 -345);
DISPLAY 0.617021 (4582 -345);
PAINT WHITE (4582 -345);
FORCEPROP 2 LAST CDS_LIB mstr_symbols
J 0
(4700 -250);
PAINT ORANGE (4700 -250);
DISPLAY INVISIBLE (4700 -250);
FORCEPROP 1 LAST COMMENT_BODY TRUE
J 0
(4725 -150);
DISPLAY 0.978723 (4725 -150);
PAINT ORANGE (4725 -150);
DISPLAY INVISIBLE (4725 -150);
FORCEADD DNS..2
(-395 -380);
PAINT RED (-395 -380);
FORCEPROP 1 LAST COMMENT_BODY TRUE
R 1
J 0
(-320 -605);
DISPLAY 0.872340 (-320 -605);
PAINT GREEN (-320 -605);
DISPLAY INVISIBLE (-320 -605);
FORCEPROP 2 LAST CDS_LIB mstr_misc
J 0
(-395 -380);
PAINT ORANGE (-395 -380);
DISPLAY INVISIBLE (-395 -380);
FORCEADD DNS..3
(4930 20);
PAINT RED (4930 20);
FORCEPROP 1 LAST COMMENT_BODY TRUE
R 1
J 0
(5005 -205);
DISPLAY 0.872340 (5005 -205);
PAINT GREEN (5005 -205);
DISPLAY INVISIBLE (5005 -205);
FORCEPROP 2 LAST CDS_LIB mstr_misc
J 0
(4930 20);
PAINT ORANGE (4930 20);
DISPLAY INVISIBLE (4930 20);
FORCEADD INTEL_CORP_BPAGE..1
(5975 -1075);
FORCEPROP 1 LAST CDS_CON_LAST_MODIFIED Tue Dec 01 11:52:28 2015
J 0
(4550 -750);
PAINT GREEN (4550 -750);
DISPLAY INVISIBLE (4550 -750);
FORCEPROP 1 LAST CUSTOM_TXT_CDS <CURRENT_DESIGN_SHEET> OF <TOTAL_DESIGN_SHEETS>
J 0
(5475 -1050);
PAINT GREEN (5475 -1050);
FORCEPROP 1 LAST CUSTOM_TXT_CDS <CON_LAST_MODIFIED>
J 0
(4050 -725);
PAINT GREEN (4050 -725);
FORCEPROP 2 LAST CUSTOM_TXT_CDS <XR_PAGE_TITLE>
J 0
(-1915 4175);
DISPLAY 0.638298 (-1915 4175);
PAINT PINK (-1915 4175);
DISPLAY INVISIBLE (-1915 4175);
FORCEPROP 1 LAST SCH_TITLE DDR VTT VR CHANNEL GHJ
J 0
(-1975 -1025);
DISPLAY 1.212766 (-1975 -1025);
PAINT GREEN (-1975 -1025);
FORCEPROP 1 LAST SCH_ADDRESS3 SANTA CLARA, CA 95052-8119
J 0
(2000 -1050);
DISPLAY 0.617021 (2000 -1050);
PAINT GREEN (2000 -1050);
FORCEPROP 1 LAST SCH_ADDRESS2 P.O. BOX 58119
J 0
(2000 -1000);
DISPLAY 0.617021 (2000 -1000);
PAINT GREEN (2000 -1000);
FORCEPROP 1 LAST SCH_ADDRESS1 2200 MISSION COLLEGE BLVD.
J 0
(2000 -950);
DISPLAY 0.617021 (2000 -950);
PAINT GREEN (2000 -950);
FORCEPROP 1 LAST SCH_NUMBER H4694802
J 0
(4675 -925);
DISPLAY 1.212766 (4675 -925);
PAINT YELLOW (4675 -925);
FORCEPROP 1 LAST SCH_DEPT BESD
J 1
(1525 -975);
DISPLAY 1.212766 (1525 -975);
PAINT YELLOW (1525 -975);
FORCEPROP 1 LAST SCH_REV 2.420
J 0
(5725 -925);
DISPLAY 0.978723 (5725 -925);
PAINT YELLOW (5725 -925);
FORCEPROP 2 LAST PAGE_BORDER TRUE
J 0
(-1915 4175);
DISPLAY 0.659574 (-1915 4175);
PAINT PINK (-1915 4175);
DISPLAY INVISIBLE (-1915 4175);
FORCEPROP 2 LAST CDS_LIB mstr_symbols
J 0
(5975 -1075);
PAINT ORANGE (5975 -1075);
DISPLAY INVISIBLE (5975 -1075);
FORCEPROP 1 LAST COMMENT_BODY TRUE
J 0
(5987 -1063);
DISPLAY 0.446809 (5987 -1063);
PAINT GREEN (5987 -1063);
DISPLAY INVISIBLE (5987 -1063);
FORCEPROP 2 LAST CDS_XR_PAGE_TITLE CR-229 : @BASEBOARD_FAB2_LIB.BASEBOARD_FAB2(SCH_1):PAGE229
J 0
(-1915 4175);
DISPLAY 0.638298 (-1915 4175);
PAINT PINK (-1915 4175);
DISPLAY INVISIBLE (-1915 4175);
WIRE 16 -1 (4225 3475)(4225 3550);
WIRE 16 -1 (4225 3550)(3825 3550);
WIRE 16 -1 (3825 3475)(3825 3550);
WIRE 16 -1 (3475 3550)(3825 3550);
WIRE 16 -1 (3475 3550)(3475 3600);
WIRE 16 -1 (3475 3550)(3475 3475);
WIRE 16 -1 (3825 1450)(3825 1525);
WIRE 16 -1 (4775 900)(4775 800);
WIRE 16 -1 (4775 800)(3925 800);
WIRE 16 -1 (3925 975)(3925 800);
WIRE 16 -1 (3925 800)(3925 725);
WIRE 16 -1 (2275 650)(2275 750);
WIRE 16 -1 (1800 925)(1950 925);
WIRE 16 -1 (1950 925)(1950 875);
WIRE 16 -1 (1800 875)(1950 875);
WIRE 16 -1 (1950 875)(1950 775);
WIRE 16 -1 (1800 775)(1950 775);
WIRE 16 -1 (1950 775)(1950 650);
WIRE 16 -1 (425 2175)(425 2275);
WIRE 16 -1 (425 1400)(425 1325);
WIRE 16 -1 (3925 1175)(3925 1325);
WIRE 16 -1 (3925 1350)(3925 1325);
WIRE 16 -1 (1800 1325)(3925 1325);
WIRE 16 -1 (4775 1350)(3925 1350);
WIRE 16 -1 (4775 1100)(4775 1350);
WIRE 16 -1 (5500 1350)(4775 1350);
WIRE 16 -1 (5500 25)(5500 1350);
WIRE 16 -1 (5500 1525)(5500 1350);
WIRE 16 -1 (5075 25)(5500 25);
WIRE 16 -1 (0 2250)(0 2150);
WIRE 16 -1 (-400 -550)(-400 -475);
WIRE 16 -1 (1200 1325)(1050 1325);
WIRE 16 -1 (1050 1325)(1050 2550);
WIRE 16 -1 (425 2550)(1050 2550);
WIRE 16 -1 (425 2475)(425 2550);
WIRE 16 -1 (0 2550)(425 2550);
WIRE 16 -1 (0 2450)(0 2550);
WIRE 16 -1 (0 2550)(-1100 2550);
WIRE 16 -1 (-1100 2550)(-1100 1575);
WIRE 16 -1 (-1100 2550)(-1475 2550);
WIRE 16 -1 (-1475 2750)(-1475 2550);
WIRE 16 -1 (-875 1575)(-1100 1575);
WIRE 16 -1 (0 1775)(-350 1775);
WIRE 16 -1 (-350 1775)(-525 1775);
WIRE 16 -1 (-350 775)(-350 1775);
WIRE 16 -1 (-525 2025)(-525 1775);
WIRE 16 -1 (3450 2125)(3450 2225);
WIRE 16 -1 (275 825)(275 900);
WIRE 16 -1 (3475 3275)(3475 3125);
WIRE 16 -1 (3475 3125)(3825 3125);
WIRE 16 -1 (3825 3275)(3825 3125);
WIRE 16 -1 (3825 3125)(4225 3125);
WIRE 16 -1 (4225 3275)(4225 3125);
WIRE 16 -1 (4225 3125)(4350 3125);
WIRE 16 -1 (4350 3075)(4350 3125);
WIRE 16 2175 (5750 3775)(5750 2850);
WIRE 16 2175 (5750 3775)(3325 3775);
WIRE 16 2175 (5750 2850)(3325 2850);
WIRE 16 2175 (3325 3775)(3325 2850);
WIRE 16 2175 (-100 1225)(850 1225);
WIRE 16 2175 (-100 1225)(-100 2850);
WIRE 16 2175 (850 1225)(850 2850);
WIRE 16 2175 (-100 2850)(850 2850);
WIRE 16 2175 (5150 -425)(5150 150);
WIRE 16 2175 (4500 -425)(5150 -425);
WIRE 16 2175 (4500 150)(5150 150);
WIRE 16 2175 (4500 -425)(4500 150);
WIRE 16 -1 (4900 1825)(4125 1825);
FORCEPROP 2 LAST SIG_NAME PWRGD_PVTT_CPU1
J 0
(4172 1835);
DISPLAY 0.617021 (4172 1835);
PAINT ORANGE (4172 1835);
WIRE 16 -1 (4775 25)(925 25);
FORCEPROP 2 LAST SIG_NAME VR_PVTT_GHJ_SNS
J 0
(977 30);
DISPLAY 0.617021 (977 30);
PAINT ORANGE (977 30);
FORCEPROP 2 LASTPROP $XRERR UNIQUE?
J 0
(737 30);
DISPLAY 0.638298 (737 30);
PAINT MONO (737 30);
DISPLAY INVISIBLE (737 30);
WIRE 16 -1 (925 975)(925 25);
WIRE 16 -1 (1200 975)(925 975);
WIRE 16 -1 (3825 1725)(3825 1825);
WIRE 16 -1 (3925 1825)(3825 1825);
WIRE 16 -1 (3825 1825)(3450 1825);
FORCEPROP 2 LAST SIG_NAME PWRGD_PVTT_GHJ_CPU1_R
J 0
(3472 1835);
DISPLAY 0.617021 (3472 1835);
PAINT ORANGE (3472 1835);
FORCEPROP 2 LASTPROP $XRERR UNIQUE?
J 0
(3232 1835);
DISPLAY 0.638298 (3232 1835);
PAINT MONO (3232 1835);
DISPLAY INVISIBLE (3232 1835);
WIRE 16 -1 (3450 1925)(3450 1825);
WIRE 16 -1 (3400 1825)(3450 1825);
WIRE 16 -1 (3400 1025)(3400 1825);
WIRE 16 -1 (1800 1025)(3400 1025);
WIRE 16 -1 (2275 950)(2275 1225);
WIRE 16 -1 (1800 1225)(2275 1225);
FORCEPROP 2 LAST SIG_NAME VR_PVTT_GHJ_VREF
J 0
(1868 1235);
DISPLAY 0.617021 (1868 1235);
PAINT ORANGE (1868 1235);
FORCEPROP 2 LASTPROP $XRERR UNIQUE?
J 0
(1628 1235);
DISPLAY 0.638298 (1628 1235);
PAINT MONO (1628 1235);
DISPLAY INVISIBLE (1628 1235);
WIRE 16 2175 (2800 1675)(2800 550);
WIRE 16 2175 (2000 1675)(2800 1675);
WIRE 16 2175 (2800 550)(2000 550);
WIRE 16 2175 (2000 550)(2000 1675);
WIRE 16 273 (2000 3425)(2000 2925);
WIRE 16 273 (2000 3525)(2000 3425);
WIRE 16 273 (850 3425)(2000 3425);
WIRE 16 273 (2000 2925)(850 2925);
WIRE 16 273 (850 2925)(850 3425);
WIRE 16 273 (850 3425)(850 3525);
WIRE 16 273 (850 3525)(2000 3525);
WIRE 16 -1 (1200 825)(975 825);
WIRE 16 -1 (975 825)(975 1775);
WIRE 16 -1 (975 1775)(425 1775);
WIRE 16 -1 (425 1600)(425 1775);
WIRE 16 -1 (200 1775)(425 1775);
FORCEPROP 2 LAST SIG_NAME VR_PVTT_GHJ_BIAS
J 0
(270 1795);
DISPLAY 0.617021 (270 1795);
PAINT ORANGE (270 1795);
FORCEPROP 2 LASTPROP $XRERR UNIQUE?
J 0
(30 1795);
DISPLAY 0.638298 (30 1795);
PAINT MONO (30 1795);
DISPLAY INVISIBLE (30 1795);
WIRE 16 -1 (275 1100)(275 1175);
WIRE 16 -1 (1200 1175)(275 1175);
FORCEPROP 2 LAST SIG_NAME VSENSE_PVDDQ_GHJ_VTT
J 0
(467 1185);
DISPLAY 0.617021 (467 1185);
PAINT ORANGE (467 1185);
FORCEPROP 2 LASTPROP $XRERR UNIQUE?
J 0
(227 1185);
DISPLAY 0.638298 (227 1185);
PAINT MONO (227 1185);
DISPLAY INVISIBLE (227 1185);
WIRE 16 -1 (275 1175)(-550 1175);
WIRE 16 -1 (-550 1175)(-550 1575);
WIRE 16 -1 (-550 1575)(-675 1575);
WIRE 16 -1 (1200 1075)(525 1075);
FORCEPROP 2 LAST SIG_NAME FM_PVTT_GHJ_EN_R
J 0
(-75 165);
DISPLAY 0.617021 (-75 165);
PAINT ORANGE (-75 165);
FORCEPROP 2 LASTPROP $XRERR UNIQUE?
J 0
(-315 165);
DISPLAY 0.638298 (-315 165);
PAINT MONO (-315 165);
DISPLAY INVISIBLE (-315 165);
WIRE 16 -1 (525 1075)(525 150);
WIRE 16 -1 (525 150)(-350 150);
WIRE 16 -1 (-350 150)(-350 575);
WIRE 16 -1 (-350 150)(-400 150);
WIRE 16 -1 (-475 150)(-400 150);
WIRE 16 -1 (-400 -275)(-400 150);
WIRE 16 -1 (-675 150)(-1400 150);
FORCEPROP 2 LAST SIG_NAME PWRGD_PVDDQ_GHJ
J 0
(-1362 165);
DISPLAY 0.617021 (-1362 165);
PAINT ORANGE (-1362 165);
DOT 1 (-400 150);
DOT 1 (-350 150);
DOT 1 (-350 1775);
DOT 1 (-1100 2550);
DOT 1 (0 2550);
DOT 1 (275 1175);
DOT 1 (425 1775);
DOT 1 (1950 775);
DOT 1 (1950 875);
DOT 1 (425 2550);
DOT 1 (850 3425);
DOT 1 (2000 3425);
DOT 1 (3925 800);
DOT 1 (3450 1825);
DOT 1 (3925 1325);
DOT 1 (3825 1825);
DOT 1 (3475 3550);
DOT 1 (3825 3125);
DOT 1 (3825 3550);
DOT 1 (4775 1350);
DOT 1 (5500 1350);
DOT 1 (4225 3125);
FORCENOTE
CRTICAL: PLACE 0 OHM NEAR  VDDQ SENSE RESISTOR.
(-1714 1394) 0;
DISPLAY LEFT (-1714 1394);
DISPLAY 1.021277 (-1714 1394);
PAINT PURPLE (-1714 1394);
FORCENOTE
IOUT TDC=+/-1.7A
(894 3106) 0;
DISPLAY LEFT (894 3106);
DISPLAY 0.808511 (894 3106);
PAINT PURPLE (894 3106);
FORCENOTE
AC & RIPPLE=+3.5/-7.3%
(894 3206) 0;
DISPLAY LEFT (894 3206);
DISPLAY 0.808511 (894 3206);
PAINT PURPLE (894 3206);
FORCENOTE
IOUT STEP=+1.523A / -1 .546A
(894 3056) 0;
DISPLAY LEFT (894 3056);
DISPLAY 0.808511 (894 3056);
PAINT PURPLE (894 3056);
FORCENOTE
IOUT PEAK=+-/1.7A
(894 3156) 0;
DISPLAY LEFT (894 3156);
DISPLAY 0.808511 (894 3156);
PAINT PURPLE (894 3156);
FORCENOTE
DC TOL= +/-1.5%
(894 3256) 0;
DISPLAY LEFT (894 3256);
DISPLAY 0.808511 (894 3256);
PAINT PURPLE (894 3256);
FORCENOTE
RIPPLE GUIDELINE= +/-1%
(894 3306) 0;
DISPLAY LEFT (894 3306);
DISPLAY 0.808511 (894 3306);
PAINT PURPLE (894 3306);
FORCENOTE
VOUT=0.5 VDDQ
(894 3356) 0;
DISPLAY LEFT (894 3356);
DISPLAY 0.808511 (894 3356);
PAINT PURPLE (894 3356);
FORCENOTE
PVTT DDR SPECIFICATION:
(894 3456) 0;
DISPLAY LEFT (894 3456);
PAINT PURPLE (894 3456);
FORCENOTE
IOUT DI/DT=6A/US
(894 3006) 0;
DISPLAY LEFT (894 3006);
DISPLAY 0.808511 (894 3006);
PAINT PURPLE (894 3006);
FORCENOTE
PLACED BETWEEN DIMMS
(4625 3520) 0;
DISPLAY LEFT (4625 3520);
DISPLAY 1.021277 (4625 3520);
PAINT PURPLE (4625 3520);
FORCENOTE
ROOM = VTT_GHJ_PWR_VR
(-1681 3633) 0;
DISPLAY LEFT (-1681 3633);
DISPLAY 1.595745 (-1681 3633);
PAINT PURPLE (-1681 3633);
QUIT
